FILE_TYPE = MACRO_DRAWING;
SET COLOR_WIRE YELLOW;
SET COLOR_PROP ORANGE;
SET COLOR_DOT WHITE;
SET COLOR_ARC YELLOW;
SET COLOR_BODY GREEN;
SET COLOR_NOTE PURPLE;
SET PROP_DISPLAY VALUE;
SET PAGE_NUMBER P28;
FORCEADD OFFPAGE..2
(-2200 2200);
FORCEPROP 2 LAST $XR0 28 
J 0
(-2011 2200);
DISPLAY 0.638298 (-2011 2200);
PAINT MONO (-2011 2200);
FORCEPROP 2 LAST CDS_LIB standard
J 0
(-2200 2200);
DISPLAY INVISIBLE (-2200 2200);
FORCEPROP 1 LAST OFFPAGE TRUE
J 0
(-1875 2075);
DISPLAY 0.872340 (-1875 2075);
PAINT GREEN (-1875 2075);
DISPLAY INVISIBLE (-1875 2075);
FORCEPROP 1 LAST COMMENT_BODY TRUE
J 0
(-2245 2105);
DISPLAY 0.872340 (-2245 2105);
PAINT GREEN (-2245 2105);
DISPLAY INVISIBLE (-2245 2105);
FORCEPROP 2 LAST PATH I10
J 0
(-2025 2275);
DISPLAY 1.021277 (-2025 2275);
DISPLAY INVISIBLE (-2025 2275);
FORCEADD OFFPAGE..1
(-7200 2750);
FORCEPROP 2 LAST $XR0 75 
J 0
(-7421 2750);
DISPLAY 0.638298 (-7421 2750);
PAINT MONO (-7421 2750);
FORCEPROP 2 LAST CDS_LIB standard
J 0
(-7200 2750);
DISPLAY INVISIBLE (-7200 2750);
FORCEPROP 1 LAST OFFPAGE TRUE
J 0
(-6875 2625);
DISPLAY 0.872340 (-6875 2625);
PAINT GREEN (-6875 2625);
DISPLAY INVISIBLE (-6875 2625);
FORCEPROP 1 LAST COMMENT_BODY TRUE
J 0
(-7075 2650);
DISPLAY 0.872340 (-7075 2650);
PAINT GREEN (-7075 2650);
DISPLAY INVISIBLE (-7075 2650);
FORCEPROP 2 LAST PATH I108
J 0
(-7150 2825);
DISPLAY 1.021277 (-7150 2825);
DISPLAY INVISIBLE (-7150 2825);
FORCEADD Q_XTAL_4P_13BI_24GND..1
(-5500 1725);
FORCEPROP 1 LAST LOCATION Y2
J 0
(-5650 2100);
DISPLAY 0.489362 (-5650 2100);
PAINT SKYBLUE (-5650 2100);
FORCEPROP 0 LAST $SEC 1
J 0
(-5650 2200);
DISPLAY 0.680851 (-5650 2200);
PAINT MONO (-5650 2200);
DISPLAY INVISIBLE (-5650 2200);
FORCEPROP 0 LAST CDS_SEC 1
J 0
(-5625 2225);
DISPLAY 1.021277 (-5625 2225);
DISPLAY INVISIBLE (-5625 2225);
FORCEPROP 0 LASTPIN (-5775 1600) $PN 2
J 2
(-5785 1610);
DISPLAY 0.489362 (-5785 1610);
PAINT MONO (-5785 1610);
FORCEPROP 0 LASTPIN (-5225 1600) $PN 4
J 0
(-5215 1610);
DISPLAY 0.489362 (-5215 1610);
PAINT MONO (-5215 1610);
FORCEPROP 0 LASTPIN (-5775 1800) $PN 1
J 2
(-5785 1810);
DISPLAY 0.489362 (-5785 1810);
PAINT MONO (-5785 1810);
FORCEPROP 0 LASTPIN (-5225 1800) $PN 3
J 0
(-5215 1810);
DISPLAY 0.489362 (-5215 1810);
PAINT MONO (-5215 1810);
FORCEPROP 2 LAST PART_TYPE SMLF
J 0
(-5650 2150);
DISPLAY 1.021277 (-5650 2150);
FORCEPROP 1 LAST MATERIAL MISC 
J 0
(-5650 1904);
DISPLAY 0.489362 (-5650 1904);
PAINT SKYBLUE (-5650 1904);
FORCEPROP 2 LAST VALUE 48MHZ
J 0
(-5650 2050);
DISPLAY 0.489362 (-5650 2050);
PAINT SKYBLUE (-5650 2050);
FORCEPROP 1 LAST PART_NUMBER BG648000055
J 0
(-5650 1975);
DISPLAY 0.489362 (-5650 1975);
PAINT SKYBLUE (-5650 1975);
FORCEPROP 1 LAST PIN_NAMES_ROTATE True
J 0
(-5500 1725);
DISPLAY 0.489362 (-5500 1725);
PAINT GREEN (-5500 1725);
DISPLAY INVISIBLE (-5500 1725);
FORCEPROP 1 LAST CDS_LMAN_SYM_OUTLINE -125,175,125,-175
J 0
(-5500 1725);
DISPLAY 0.468085 (-5500 1725);
PAINT GREEN (-5500 1725);
DISPLAY INVISIBLE (-5500 1725);
FORCEPROP 2 LAST CDS_LIB pure_quanta
J 0
(-5500 1725);
DISPLAY INVISIBLE (-5500 1725);
FORCEPROP 1 LAST PATH I11
J 0
(-5375 1550);
DISPLAY 0.723404 (-5375 1550);
PAINT GREEN (-5375 1550);
DISPLAY INVISIBLE (-5375 1550);
FORCEADD OFFPAGE..2
(-7600 2500);
FORCEPROP 2 LAST $XR1 136 
J 0
(-7321 2500);
DISPLAY 0.638298 (-7321 2500);
PAINT MONO (-7321 2500);
FORCEPROP 2 LAST $XR0 28 
J 0
(-7411 2500);
DISPLAY 0.638298 (-7411 2500);
PAINT MONO (-7411 2500);
FORCEPROP 2 LAST PATH I117
J 2
(-7400 2550);
DISPLAY 1.021277 (-7400 2550);
DISPLAY INVISIBLE (-7400 2550);
FORCEPROP 1 LAST COMMENT_BODY TRUE
J 0
(-7645 2405);
DISPLAY 0.872340 (-7645 2405);
PAINT PEACH (-7645 2405);
DISPLAY INVISIBLE (-7645 2405);
FORCEPROP 1 LAST OFFPAGE TRUE
J 0
(-7275 2375);
DISPLAY 0.872340 (-7275 2375);
PAINT GREEN (-7275 2375);
DISPLAY INVISIBLE (-7275 2375);
FORCEPROP 2 LAST CDS_LIB standard
J 0
(-7600 2500);
DISPLAY INVISIBLE (-7600 2500);
FORCEADD OFFPAGE..2
(-7600 2550);
FORCEPROP 2 LAST $XR1 136 
J 0
(-7321 2550);
DISPLAY 0.638298 (-7321 2550);
PAINT MONO (-7321 2550);
FORCEPROP 2 LAST $XR0 28 
J 0
(-7411 2550);
DISPLAY 0.638298 (-7411 2550);
PAINT MONO (-7411 2550);
FORCEPROP 2 LAST PATH I118
J 2
(-7400 2600);
DISPLAY 1.021277 (-7400 2600);
DISPLAY INVISIBLE (-7400 2600);
FORCEPROP 1 LAST COMMENT_BODY TRUE
J 0
(-7645 2455);
DISPLAY 0.872340 (-7645 2455);
PAINT PEACH (-7645 2455);
DISPLAY INVISIBLE (-7645 2455);
FORCEPROP 1 LAST OFFPAGE TRUE
J 0
(-7275 2425);
DISPLAY 0.872340 (-7275 2425);
PAINT GREEN (-7275 2425);
DISPLAY INVISIBLE (-7275 2425);
FORCEPROP 2 LAST CDS_LIB standard
J 0
(-7600 2550);
DISPLAY INVISIBLE (-7600 2550);
FORCEADD Q_RES..2
(-8500 2725);
FORCEPROP 1 LAST LOCATION R425
J 0
(-8455 2800);
DISPLAY 0.489362 (-8455 2800);
PAINT SKYBLUE (-8455 2800);
FORCEPROP 0 LAST $SEC 1
J 0
(-8450 2875);
DISPLAY 0.680851 (-8450 2875);
PAINT MONO (-8450 2875);
DISPLAY INVISIBLE (-8450 2875);
FORCEPROP 0 LAST CDS_SEC 1
J 0
(-8450 2875);
DISPLAY 1.021277 (-8450 2875);
DISPLAY INVISIBLE (-8450 2875);
FORCEPROP 1 LASTPIN (-8500 2825) $PN 1
J 0
(-8495 2787);
DISPLAY 0.489362 (-8495 2787);
PAINT MONO (-8495 2787);
FORCEPROP 1 LASTPIN (-8500 2625) $PN 2
J 0
(-8495 2635);
DISPLAY 0.489362 (-8495 2635);
PAINT MONO (-8495 2635);
FORCEPROP 1 LAST VALUE 1K
J 0
(-8450 2775);
DISPLAY 0.489362 (-8450 2775);
PAINT SKYBLUE (-8450 2775);
FORCEPROP 1 LAST TOLERANCE 5%
J 0
(-8450 2750);
DISPLAY 0.489362 (-8450 2750);
PAINT SKYBLUE (-8450 2750);
FORCEPROP 1 LAST MATERIAL EMPTY
J 0
(-8450 2700);
DISPLAY 0.489362 (-8450 2700);
PAINT RED (-8450 2700);
FORCEPROP 1 LAST WATTAGE 1/16W
J 0
(-8450 2725);
DISPLAY 0.489362 (-8450 2725);
PAINT SKYBLUE (-8450 2725);
DISPLAY INVISIBLE (-8450 2725);
FORCEPROP 1 LAST PACK_TYPE 0402LF
J 0
(-8450 2675);
DISPLAY 0.489362 (-8450 2675);
PAINT SKYBLUE (-8450 2675);
DISPLAY INVISIBLE (-8450 2675);
FORCEPROP 2 LAST CDS_LIB pure_quanta
J 0
(-8500 2725);
DISPLAY INVISIBLE (-8500 2725);
FORCEPROP 1 LAST PATH I119
J 0
(-8450 2900);
DISPLAY 0.978723 (-8450 2900);
PAINT WHITE (-8450 2900);
DISPLAY INVISIBLE (-8450 2900);
FORCEPROP 1 LAST PART_NUMBER TMP_QCS21002JB34
J 0
(-8450 2650);
DISPLAY 0.489362 (-8450 2650);
PAINT SKYBLUE (-8450 2650);
DISPLAY INVISIBLE (-8450 2650);
FORCEADD OFFPAGE..1
(-6300 5050);
FORCEPROP 2 LAST $XR0 28 
J 0
(-6521 5050);
DISPLAY 0.638298 (-6521 5050);
PAINT MONO (-6521 5050);
FORCEPROP 2 LAST CDS_LIB standard
J 0
(-6300 5050);
DISPLAY INVISIBLE (-6300 5050);
FORCEPROP 1 LAST OFFPAGE TRUE
J 0
(-5975 4925);
DISPLAY 0.872340 (-5975 4925);
PAINT GREEN (-5975 4925);
DISPLAY INVISIBLE (-5975 4925);
FORCEPROP 1 LAST COMMENT_BODY TRUE
J 0
(-6175 4950);
DISPLAY 0.872340 (-6175 4950);
PAINT GREEN (-6175 4950);
DISPLAY INVISIBLE (-6175 4950);
FORCEPROP 2 LAST PATH I12
J 0
(-6250 5125);
DISPLAY 1.021277 (-6250 5125);
DISPLAY INVISIBLE (-6250 5125);
FORCEADD Q_RES..2
(-8850 2725);
FORCEPROP 1 LAST LOCATION R421
J 0
(-8800 2800);
DISPLAY 0.489362 (-8800 2800);
PAINT SKYBLUE (-8800 2800);
FORCEPROP 0 LAST $SEC 1
J 2
(-8800 2850);
DISPLAY 0.680851 (-8800 2850);
PAINT MONO (-8800 2850);
DISPLAY INVISIBLE (-8800 2850);
FORCEPROP 0 LAST CDS_SEC 1
J 2
(-8800 2850);
DISPLAY 1.021277 (-8800 2850);
DISPLAY INVISIBLE (-8800 2850);
FORCEPROP 1 LASTPIN (-8850 2825) $PN 1
J 0
(-8845 2787);
DISPLAY 0.489362 (-8845 2787);
PAINT MONO (-8845 2787);
FORCEPROP 1 LASTPIN (-8850 2625) $PN 2
J 0
(-8845 2635);
DISPLAY 0.489362 (-8845 2635);
PAINT MONO (-8845 2635);
FORCEPROP 1 LAST VALUE 1K
J 0
(-8800 2775);
DISPLAY 0.489362 (-8800 2775);
PAINT SKYBLUE (-8800 2775);
FORCEPROP 1 LAST TOLERANCE 5%
J 0
(-8800 2750);
DISPLAY 0.489362 (-8800 2750);
PAINT SKYBLUE (-8800 2750);
FORCEPROP 1 LAST MATERIAL EMPTY
J 0
(-8800 2700);
DISPLAY 0.489362 (-8800 2700);
PAINT RED (-8800 2700);
FORCEPROP 2 LAST CDS_LIB pure_quanta
J 2
(-8850 2725);
DISPLAY INVISIBLE (-8850 2725);
FORCEPROP 1 LAST PATH I120
J 0
(-8800 2900);
DISPLAY 0.978723 (-8800 2900);
PAINT WHITE (-8800 2900);
DISPLAY INVISIBLE (-8800 2900);
FORCEPROP 1 LAST WATTAGE 1/16W
J 0
(-8800 2725);
DISPLAY 0.489362 (-8800 2725);
PAINT SKYBLUE (-8800 2725);
DISPLAY INVISIBLE (-8800 2725);
FORCEPROP 1 LAST PACK_TYPE 0402LF
J 0
(-8800 2675);
DISPLAY 0.489362 (-8800 2675);
PAINT SKYBLUE (-8800 2675);
DISPLAY INVISIBLE (-8800 2675);
FORCEPROP 1 LAST PART_NUMBER TMP_QCS21002JB34
J 0
(-8800 2650);
DISPLAY 0.489362 (-8800 2650);
PAINT SKYBLUE (-8800 2650);
DISPLAY INVISIBLE (-8800 2650);
FORCEADD Q_RES..2
(-8675 2725);
FORCEPROP 1 LAST LOCATION R423
J 0
(-8630 2800);
DISPLAY 0.489362 (-8630 2800);
PAINT SKYBLUE (-8630 2800);
FORCEPROP 0 LAST $SEC 1
J 0
(-8625 2875);
DISPLAY 0.680851 (-8625 2875);
PAINT MONO (-8625 2875);
DISPLAY INVISIBLE (-8625 2875);
FORCEPROP 0 LAST CDS_SEC 1
J 0
(-8625 2875);
DISPLAY 1.021277 (-8625 2875);
DISPLAY INVISIBLE (-8625 2875);
FORCEPROP 1 LASTPIN (-8675 2825) $PN 1
J 0
(-8670 2787);
DISPLAY 0.489362 (-8670 2787);
PAINT MONO (-8670 2787);
FORCEPROP 1 LASTPIN (-8675 2625) $PN 2
J 0
(-8670 2635);
DISPLAY 0.489362 (-8670 2635);
PAINT MONO (-8670 2635);
FORCEPROP 1 LAST TOLERANCE 5%
J 0
(-8625 2750);
DISPLAY 0.489362 (-8625 2750);
PAINT SKYBLUE (-8625 2750);
FORCEPROP 1 LAST VALUE 1K
J 0
(-8625 2775);
DISPLAY 0.489362 (-8625 2775);
PAINT SKYBLUE (-8625 2775);
FORCEPROP 1 LAST MATERIAL EMPTY
J 0
(-8625 2700);
DISPLAY 0.489362 (-8625 2700);
PAINT RED (-8625 2700);
FORCEPROP 2 LAST CDS_LIB pure_quanta
J 0
(-8675 2725);
DISPLAY INVISIBLE (-8675 2725);
FORCEPROP 1 LAST PATH I121
J 0
(-8625 2900);
DISPLAY 0.978723 (-8625 2900);
PAINT WHITE (-8625 2900);
DISPLAY INVISIBLE (-8625 2900);
FORCEPROP 1 LAST WATTAGE 1/16W
J 0
(-8625 2725);
DISPLAY 0.489362 (-8625 2725);
PAINT SKYBLUE (-8625 2725);
DISPLAY INVISIBLE (-8625 2725);
FORCEPROP 1 LAST PACK_TYPE 0402LF
J 0
(-8625 2675);
DISPLAY 0.489362 (-8625 2675);
PAINT SKYBLUE (-8625 2675);
DISPLAY INVISIBLE (-8625 2675);
FORCEPROP 1 LAST PART_NUMBER TMP_QCS21002JB34
J 0
(-8625 2650);
DISPLAY 0.489362 (-8625 2650);
PAINT SKYBLUE (-8625 2650);
DISPLAY INVISIBLE (-8625 2650);
FORCEADD Q_RES..2
(-9025 2725);
FORCEPROP 1 LAST LOCATION R420
J 0
(-8975 2800);
DISPLAY 0.489362 (-8975 2800);
PAINT SKYBLUE (-8975 2800);
FORCEPROP 0 LAST $SEC 1
J 2
(-8975 2850);
DISPLAY 0.680851 (-8975 2850);
PAINT MONO (-8975 2850);
DISPLAY INVISIBLE (-8975 2850);
FORCEPROP 0 LAST CDS_SEC 1
J 2
(-8975 2850);
DISPLAY 1.021277 (-8975 2850);
DISPLAY INVISIBLE (-8975 2850);
FORCEPROP 1 LASTPIN (-9025 2825) $PN 1
J 0
(-9020 2787);
DISPLAY 0.489362 (-9020 2787);
PAINT MONO (-9020 2787);
FORCEPROP 1 LASTPIN (-9025 2625) $PN 2
J 0
(-9020 2635);
DISPLAY 0.489362 (-9020 2635);
PAINT MONO (-9020 2635);
FORCEPROP 1 LAST TOLERANCE 5%
J 0
(-8975 2750);
DISPLAY 0.489362 (-8975 2750);
PAINT SKYBLUE (-8975 2750);
FORCEPROP 1 LAST VALUE 1K
J 0
(-8975 2775);
DISPLAY 0.489362 (-8975 2775);
PAINT SKYBLUE (-8975 2775);
FORCEPROP 1 LAST MATERIAL EMPTY
J 0
(-8975 2700);
DISPLAY 0.489362 (-8975 2700);
PAINT RED (-8975 2700);
FORCEPROP 2 LAST CDS_LIB pure_quanta
J 2
(-9025 2725);
DISPLAY INVISIBLE (-9025 2725);
FORCEPROP 1 LAST PATH I123
J 0
(-8975 2900);
DISPLAY 0.978723 (-8975 2900);
PAINT WHITE (-8975 2900);
DISPLAY INVISIBLE (-8975 2900);
FORCEPROP 1 LAST WATTAGE 1/16W
J 0
(-8975 2725);
DISPLAY 0.489362 (-8975 2725);
PAINT SKYBLUE (-8975 2725);
DISPLAY INVISIBLE (-8975 2725);
FORCEPROP 1 LAST PACK_TYPE 0402LF
J 0
(-8975 2675);
DISPLAY 0.489362 (-8975 2675);
PAINT SKYBLUE (-8975 2675);
DISPLAY INVISIBLE (-8975 2675);
FORCEPROP 1 LAST PART_NUMBER TMP_QCS21002JB34
J 0
(-8975 2650);
DISPLAY 0.489362 (-8975 2650);
PAINT SKYBLUE (-8975 2650);
DISPLAY INVISIBLE (-8975 2650);
FORCEADD OFFPAGE..1
(-6300 5000);
FORCEPROP 2 LAST $XR0 28 
J 0
(-6521 5000);
DISPLAY 0.638298 (-6521 5000);
PAINT MONO (-6521 5000);
FORCEPROP 2 LAST CDS_LIB standard
J 0
(-6300 5000);
DISPLAY INVISIBLE (-6300 5000);
FORCEPROP 1 LAST OFFPAGE TRUE
J 0
(-5975 4875);
DISPLAY 0.872340 (-5975 4875);
PAINT GREEN (-5975 4875);
DISPLAY INVISIBLE (-5975 4875);
FORCEPROP 1 LAST COMMENT_BODY TRUE
J 0
(-6175 4900);
DISPLAY 0.872340 (-6175 4900);
PAINT GREEN (-6175 4900);
DISPLAY INVISIBLE (-6175 4900);
FORCEPROP 2 LAST PATH I13
J 0
(-6250 5075);
DISPLAY 1.021277 (-6250 5075);
DISPLAY INVISIBLE (-6250 5075);
FORCEADD VCC_CORE..1
(-8500 3025);
FORCEPROP 3 LASTPIN (-8500 2975) SIG_NAME PVDD11_S3_P0\g
J 0
(-8490 2985);
DISPLAY 0.659574 (-8490 2985);
PAINT MONO (-8490 2985);
DISPLAY INVISIBLE (-8490 2985);
FORCEPROP 1 LAST HDL_POWER PVDD11_S3_P0
J 1
(-8500 3075);
DISPLAY 0.489362 (-8500 3075);
PAINT GREEN (-8500 3075);
FORCEPROP 2 LAST CDS_LIB pure_quanta_power
J 0
(-8500 3025);
DISPLAY INVISIBLE (-8500 3025);
FORCEPROP 1 LAST PATH I130
J 0
(-8450 3050);
DISPLAY 0.872340 (-8450 3050);
PAINT AQUA (-8450 3050);
DISPLAY INVISIBLE (-8450 3050);
FORCEADD OFFPAGE..2
(-7600 2450);
FORCEPROP 2 LAST $XR1 136 
J 0
(-7321 2450);
DISPLAY 0.638298 (-7321 2450);
PAINT MONO (-7321 2450);
FORCEPROP 2 LAST $XR0 28 
J 0
(-7411 2450);
DISPLAY 0.638298 (-7411 2450);
PAINT MONO (-7411 2450);
FORCEPROP 2 LAST PATH I131
J 0
(-7425 2525);
DISPLAY 1.021277 (-7425 2525);
DISPLAY INVISIBLE (-7425 2525);
FORCEPROP 1 LAST COMMENT_BODY TRUE
J 0
(-7645 2355);
DISPLAY 0.872340 (-7645 2355);
PAINT PEACH (-7645 2355);
DISPLAY INVISIBLE (-7645 2355);
FORCEPROP 1 LAST OFFPAGE TRUE
J 0
(-7275 2325);
DISPLAY 0.872340 (-7275 2325);
PAINT GREEN (-7275 2325);
DISPLAY INVISIBLE (-7275 2325);
FORCEPROP 2 LAST CDS_LIB standard
J 0
(-7600 2450);
DISPLAY INVISIBLE (-7600 2450);
FORCEADD OFFPAGE..2
(-7600 2400);
FORCEPROP 2 LAST $XR1 136 
J 0
(-7321 2400);
DISPLAY 0.638298 (-7321 2400);
PAINT MONO (-7321 2400);
FORCEPROP 2 LAST $XR0 28 
J 0
(-7411 2400);
DISPLAY 0.638298 (-7411 2400);
PAINT MONO (-7411 2400);
FORCEPROP 2 LAST PATH I132
J 0
(-7425 2475);
DISPLAY 1.021277 (-7425 2475);
DISPLAY INVISIBLE (-7425 2475);
FORCEPROP 1 LAST COMMENT_BODY TRUE
J 0
(-7645 2305);
DISPLAY 0.872340 (-7645 2305);
PAINT PEACH (-7645 2305);
DISPLAY INVISIBLE (-7645 2305);
FORCEPROP 1 LAST OFFPAGE TRUE
J 0
(-7275 2275);
DISPLAY 0.872340 (-7275 2275);
PAINT GREEN (-7275 2275);
DISPLAY INVISIBLE (-7275 2275);
FORCEPROP 2 LAST CDS_LIB standard
J 0
(-7600 2400);
DISPLAY INVISIBLE (-7600 2400);
FORCEADD UNIVERSAL_GND..1
(-5875 1400);
FORCEPROP 3 LASTPIN (-5875 1450) SIG_NAME GND\g
J 0
(-5865 1460);
DISPLAY 0.659574 (-5865 1460);
PAINT MONO (-5865 1460);
DISPLAY INVISIBLE (-5865 1460);
FORCEPROP 2 LAST CDS_LIB pure_quanta_power
J 0
(-5875 1400);
DISPLAY INVISIBLE (-5875 1400);
FORCEPROP 1 LAST PATH I14
J 0
(-5800 1400);
DISPLAY 0.872340 (-5800 1400);
PAINT AQUA (-5800 1400);
DISPLAY INVISIBLE (-5800 1400);
FORCEPROP 1 LAST HDL_POWER GND
J 1
(-5850 1325);
DISPLAY 0.872340 (-5850 1325);
PAINT GREEN (-5850 1325);
DISPLAY INVISIBLE (-5850 1325);
FORCEADD UNIVERSAL_GND..1
(-5075 1375);
FORCEPROP 3 LASTPIN (-5075 1425) SIG_NAME GND\g
J 0
(-5065 1435);
DISPLAY 0.659574 (-5065 1435);
PAINT MONO (-5065 1435);
DISPLAY INVISIBLE (-5065 1435);
FORCEPROP 2 LAST CDS_LIB pure_quanta_power
J 0
(-5075 1375);
DISPLAY INVISIBLE (-5075 1375);
FORCEPROP 1 LAST PATH I15
J 0
(-5000 1375);
DISPLAY 0.872340 (-5000 1375);
PAINT AQUA (-5000 1375);
DISPLAY INVISIBLE (-5000 1375);
FORCEPROP 1 LAST HDL_POWER GND
J 1
(-5050 1300);
DISPLAY 0.872340 (-5050 1300);
PAINT GREEN (-5050 1300);
DISPLAY INVISIBLE (-5050 1300);
FORCEADD OFFPAGE..4
R 2
(-6625 4650);
FORCEPROP 2 LAST $XR1 80 
J 0
(-6936 4650);
DISPLAY 0.638298 (-6936 4650);
PAINT MONO (-6936 4650);
FORCEPROP 2 LAST $XR0 28 
J 0
(-6846 4650);
DISPLAY 0.638298 (-6846 4650);
PAINT MONO (-6846 4650);
FORCEPROP 2 LAST CDS_LIB standard
J 0
(-6625 4650);
DISPLAY INVISIBLE (-6625 4650);
FORCEPROP 1 LAST OFFPAGE TRUE
J 2
(-6950 4525);
DISPLAY 0.872340 (-6950 4525);
PAINT GREEN (-6950 4525);
DISPLAY INVISIBLE (-6950 4525);
FORCEPROP 1 LAST COMMENT_BODY TRUE
J 2
(-6600 4550);
DISPLAY 0.872340 (-6600 4550);
PAINT GREEN (-6600 4550);
DISPLAY INVISIBLE (-6600 4550);
FORCEPROP 2 LAST PATH I152
J 0
(-6875 4700);
DISPLAY 1.021277 (-6875 4700);
DISPLAY INVISIBLE (-6875 4700);
FORCEADD OFFPAGE..4
R 2
(-7225 3350);
FORCEPROP 2 LAST $XR1 81 
J 0
(-7566 3350);
DISPLAY 0.638298 (-7566 3350);
PAINT MONO (-7566 3350);
FORCEPROP 2 LAST $XR0 28 
J 0
(-7476 3350);
DISPLAY 0.638298 (-7476 3350);
PAINT MONO (-7476 3350);
FORCEPROP 2 LAST CDS_LIB standard
J 0
(-7225 3350);
DISPLAY INVISIBLE (-7225 3350);
FORCEPROP 1 LAST OFFPAGE TRUE
J 2
(-7550 3225);
DISPLAY 0.872340 (-7550 3225);
PAINT GREEN (-7550 3225);
DISPLAY INVISIBLE (-7550 3225);
FORCEPROP 1 LAST COMMENT_BODY TRUE
J 2
(-7200 3250);
DISPLAY 0.872340 (-7200 3250);
PAINT GREEN (-7200 3250);
DISPLAY INVISIBLE (-7200 3250);
FORCEPROP 2 LAST PATH I158
J 0
(-7475 3400);
DISPLAY 1.021277 (-7475 3400);
DISPLAY INVISIBLE (-7475 3400);
FORCEADD OFFPAGE..4
R 2
(-7225 3300);
FORCEPROP 2 LAST $XR1 81 
J 0
(-7566 3300);
DISPLAY 0.638298 (-7566 3300);
PAINT MONO (-7566 3300);
FORCEPROP 2 LAST $XR0 28 
J 0
(-7476 3300);
DISPLAY 0.638298 (-7476 3300);
PAINT MONO (-7476 3300);
FORCEPROP 2 LAST CDS_LIB standard
J 0
(-7225 3300);
DISPLAY INVISIBLE (-7225 3300);
FORCEPROP 1 LAST OFFPAGE TRUE
J 2
(-7550 3175);
DISPLAY 0.872340 (-7550 3175);
PAINT GREEN (-7550 3175);
DISPLAY INVISIBLE (-7550 3175);
FORCEPROP 1 LAST COMMENT_BODY TRUE
J 2
(-7200 3200);
DISPLAY 0.872340 (-7200 3200);
PAINT GREEN (-7200 3200);
DISPLAY INVISIBLE (-7200 3200);
FORCEPROP 2 LAST PATH I159
J 0
(-7475 3350);
DISPLAY 1.021277 (-7475 3350);
DISPLAY INVISIBLE (-7475 3350);
FORCEADD Q_CAP..1
(-6150 975);
FORCEPROP 1 LAST LOCATION C213
J 0
(-6100 1075);
DISPLAY 0.489362 (-6100 1075);
PAINT SKYBLUE (-6100 1075);
FORCEPROP 0 LAST $SEC 1
J 0
(-6100 1125);
DISPLAY 0.680851 (-6100 1125);
PAINT MONO (-6100 1125);
DISPLAY INVISIBLE (-6100 1125);
FORCEPROP 0 LAST CDS_SEC 1
J 0
(-6100 1125);
DISPLAY 1.021277 (-6100 1125);
DISPLAY INVISIBLE (-6100 1125);
FORCEPROP 1 LASTPIN (-6150 1075) $PN 1
J 0
(-6140 1055);
DISPLAY 0.489362 (-6140 1055);
PAINT MONO (-6140 1055);
FORCEPROP 1 LASTPIN (-6150 875) $PN 2
J 0
(-6140 855);
DISPLAY 0.489362 (-6140 855);
PAINT MONO (-6140 855);
FORCEPROP 1 LAST PART_NUMBER CH-3916TB01
J 0
(-6100 825);
DISPLAY 0.489362 (-6100 825);
PAINT SKYBLUE (-6100 825);
FORCEPROP 1 LAST PACK_TYPE C0402
J 0
(-6100 775);
DISPLAY 0.489362 (-6100 775);
PAINT SKYBLUE (-6100 775);
FORCEPROP 1 LAST VOLTAGE 50V
J 0
(-6100 975);
DISPLAY 0.489362 (-6100 975);
PAINT SKYBLUE (-6100 975);
FORCEPROP 1 LAST VALUE 3.9P
J 0
(-6100 1025);
DISPLAY 0.489362 (-6100 1025);
PAINT SKYBLUE (-6100 1025);
FORCEPROP 1 LAST TOLERANCE 0.1P
J 0
(-6100 925);
DISPLAY 0.489362 (-6100 925);
PAINT SKYBLUE (-6100 925);
FORCEPROP 1 LAST MATERIAL NPO
J 0
(-6100 875);
DISPLAY 0.489362 (-6100 875);
PAINT SKYBLUE (-6100 875);
FORCEPROP 1 LAST PATH I16
J 0
(-6100 1125);
DISPLAY 0.978723 (-6100 1125);
PAINT WHITE (-6100 1125);
DISPLAY INVISIBLE (-6100 1125);
FORCEPROP 2 LAST CDS_LIB pure_quanta
J 0
(-6150 975);
DISPLAY INVISIBLE (-6150 975);
FORCEADD OFFPAGE..4
R 2
(-7225 3250);
FORCEPROP 2 LAST $XR1 81 
J 0
(-7566 3250);
DISPLAY 0.638298 (-7566 3250);
PAINT MONO (-7566 3250);
FORCEPROP 2 LAST $XR0 28 
J 0
(-7476 3250);
DISPLAY 0.638298 (-7476 3250);
PAINT MONO (-7476 3250);
FORCEPROP 2 LAST CDS_LIB standard
J 0
(-7225 3250);
DISPLAY INVISIBLE (-7225 3250);
FORCEPROP 1 LAST OFFPAGE TRUE
J 2
(-7550 3125);
DISPLAY 0.872340 (-7550 3125);
PAINT GREEN (-7550 3125);
DISPLAY INVISIBLE (-7550 3125);
FORCEPROP 1 LAST COMMENT_BODY TRUE
J 2
(-7200 3150);
DISPLAY 0.872340 (-7200 3150);
PAINT GREEN (-7200 3150);
DISPLAY INVISIBLE (-7200 3150);
FORCEPROP 2 LAST PATH I160
J 0
(-7475 3300);
DISPLAY 1.021277 (-7475 3300);
DISPLAY INVISIBLE (-7475 3300);
FORCEADD OFFPAGE..4
R 2
(-7225 3200);
FORCEPROP 2 LAST $XR1 81 
J 0
(-7566 3200);
DISPLAY 0.638298 (-7566 3200);
PAINT MONO (-7566 3200);
FORCEPROP 2 LAST $XR0 28 
J 0
(-7476 3200);
DISPLAY 0.638298 (-7476 3200);
PAINT MONO (-7476 3200);
FORCEPROP 2 LAST CDS_LIB standard
J 0
(-7225 3200);
DISPLAY INVISIBLE (-7225 3200);
FORCEPROP 1 LAST OFFPAGE TRUE
J 2
(-7550 3075);
DISPLAY 0.872340 (-7550 3075);
PAINT GREEN (-7550 3075);
DISPLAY INVISIBLE (-7550 3075);
FORCEPROP 1 LAST COMMENT_BODY TRUE
J 2
(-7200 3100);
DISPLAY 0.872340 (-7200 3100);
PAINT GREEN (-7200 3100);
DISPLAY INVISIBLE (-7200 3100);
FORCEPROP 2 LAST PATH I161
J 0
(-7475 3250);
DISPLAY 1.021277 (-7475 3250);
DISPLAY INVISIBLE (-7475 3250);
FORCEADD UNIVERSAL_GND..1
(-6150 675);
FORCEPROP 3 LASTPIN (-6150 725) SIG_NAME GND\g
J 0
(-6140 735);
DISPLAY 0.659574 (-6140 735);
PAINT MONO (-6140 735);
DISPLAY INVISIBLE (-6140 735);
FORCEPROP 2 LAST CDS_LIB pure_quanta_power
J 0
(-6150 675);
DISPLAY INVISIBLE (-6150 675);
FORCEPROP 1 LAST PATH I17
J 0
(-6075 675);
DISPLAY 0.872340 (-6075 675);
PAINT AQUA (-6075 675);
DISPLAY INVISIBLE (-6075 675);
FORCEPROP 1 LAST HDL_POWER GND
J 1
(-6125 600);
DISPLAY 0.872340 (-6125 600);
PAINT GREEN (-6125 600);
DISPLAY INVISIBLE (-6125 600);
FORCEADD OFFPAGE..2
R 2
(-6275 3700);
FORCEPROP 2 LAST $XR1 80 
J 0
(-6619 3700);
DISPLAY 0.638298 (-6619 3700);
PAINT MONO (-6619 3700);
FORCEPROP 2 LAST $XR0 28 
J 0
(-6529 3700);
DISPLAY 0.638298 (-6529 3700);
PAINT MONO (-6529 3700);
FORCEPROP 2 LAST CDS_LIB standard
J 0
(-6275 3700);
DISPLAY INVISIBLE (-6275 3700);
FORCEPROP 1 LAST OFFPAGE TRUE
J 2
(-6600 3575);
DISPLAY 0.872340 (-6600 3575);
PAINT GREEN (-6600 3575);
DISPLAY INVISIBLE (-6600 3575);
FORCEPROP 1 LAST COMMENT_BODY TRUE
J 2
(-6230 3605);
DISPLAY 0.872340 (-6230 3605);
PAINT GREEN (-6230 3605);
DISPLAY INVISIBLE (-6230 3605);
FORCEPROP 2 LAST PATH I174
J 0
(-6225 3775);
DISPLAY 1.021277 (-6225 3775);
DISPLAY INVISIBLE (-6225 3775);
FORCEADD Q_CAP..1
(-4875 975);
FORCEPROP 1 LAST LOCATION C214
J 0
(-4825 1075);
DISPLAY 0.489362 (-4825 1075);
PAINT SKYBLUE (-4825 1075);
FORCEPROP 0 LAST $SEC 1
J 0
(-4825 1125);
DISPLAY 0.680851 (-4825 1125);
PAINT MONO (-4825 1125);
DISPLAY INVISIBLE (-4825 1125);
FORCEPROP 0 LAST CDS_SEC 1
J 0
(-4825 1125);
DISPLAY 1.021277 (-4825 1125);
DISPLAY INVISIBLE (-4825 1125);
FORCEPROP 1 LASTPIN (-4875 1075) $PN 1
J 0
(-4865 1055);
DISPLAY 0.489362 (-4865 1055);
PAINT MONO (-4865 1055);
FORCEPROP 1 LASTPIN (-4875 875) $PN 2
J 0
(-4865 855);
DISPLAY 0.489362 (-4865 855);
PAINT MONO (-4865 855);
FORCEPROP 1 LAST MATERIAL NPO
J 0
(-4825 875);
DISPLAY 0.489362 (-4825 875);
PAINT SKYBLUE (-4825 875);
FORCEPROP 1 LAST TOLERANCE 0.1P
J 0
(-4825 925);
DISPLAY 0.489362 (-4825 925);
PAINT SKYBLUE (-4825 925);
FORCEPROP 1 LAST VALUE 3.9P
J 0
(-4825 1025);
DISPLAY 0.489362 (-4825 1025);
PAINT SKYBLUE (-4825 1025);
FORCEPROP 1 LAST PART_NUMBER CH-3916TB01
J 0
(-4825 825);
DISPLAY 0.489362 (-4825 825);
PAINT SKYBLUE (-4825 825);
FORCEPROP 1 LAST VOLTAGE 50V
J 0
(-4825 975);
DISPLAY 0.489362 (-4825 975);
PAINT SKYBLUE (-4825 975);
FORCEPROP 1 LAST PACK_TYPE C0402
J 0
(-4825 775);
DISPLAY 0.489362 (-4825 775);
PAINT SKYBLUE (-4825 775);
FORCEPROP 2 LAST CDS_LIB pure_quanta
J 0
(-4875 975);
DISPLAY INVISIBLE (-4875 975);
FORCEPROP 1 LAST PATH I18
J 0
(-4825 1125);
DISPLAY 0.978723 (-4825 1125);
PAINT WHITE (-4825 1125);
DISPLAY INVISIBLE (-4825 1125);
FORCEADD GENOA_SP5..21
(-4275 4450);
FORCEPROP 1 LAST LOCATION U25
J 0
(-5370 6477);
DISPLAY 0.489362 (-5370 6477);
PAINT SKYBLUE (-5370 6477);
FORCEPROP 0 LAST $SEC 21
J 0
(-5350 6525);
DISPLAY 0.680851 (-5350 6525);
PAINT MONO (-5350 6525);
DISPLAY INVISIBLE (-5350 6525);
FORCEPROP 0 LAST CDS_SEC 21
J 0
(-5375 6150);
DISPLAY 1.021277 (-5375 6150);
DISPLAY INVISIBLE (-5375 6150);
FORCEPROP 0 LASTPIN (-5525 3450) $PN DE36
J 2
(-5535 3460);
DISPLAY 0.489362 (-5535 3460);
PAINT MONO (-5535 3460);
FORCEPROP 0 LASTPIN (-5525 3400) $PN DF36
J 2
(-5535 3410);
DISPLAY 0.489362 (-5535 3410);
PAINT MONO (-5535 3410);
FORCEPROP 0 LASTPIN (-5525 3350) $PN DF40
J 2
(-5535 3360);
DISPLAY 0.489362 (-5535 3360);
PAINT MONO (-5535 3360);
FORCEPROP 0 LASTPIN (-5525 3300) $PN DE40
J 2
(-5535 3310);
DISPLAY 0.489362 (-5535 3310);
PAINT MONO (-5535 3310);
FORCEPROP 0 LASTPIN (-5525 2700) $PN DH4
J 2
(-5535 2710);
DISPLAY 0.489362 (-5535 2710);
PAINT MONO (-5535 2710);
FORCEPROP 0 LASTPIN (-5525 3150) $PN DF33
J 2
(-5535 3160);
DISPLAY 0.489362 (-5535 3160);
PAINT MONO (-5535 3160);
FORCEPROP 0 LASTPIN (-5525 3100) $PN DE32
J 2
(-5535 3110);
DISPLAY 0.489362 (-5535 3110);
PAINT MONO (-5535 3110);
FORCEPROP 0 LASTPIN (-5525 3050) $PN DG11
J 2
(-5535 3060);
DISPLAY 0.489362 (-5535 3060);
PAINT MONO (-5535 3060);
FORCEPROP 0 LASTPIN (-5525 3000) $PN DJ29
J 2
(-5535 3010);
DISPLAY 0.489362 (-5535 3010);
PAINT MONO (-5535 3010);
FORCEPROP 0 LASTPIN (-5525 2950) $PN DH30
J 2
(-5535 2960);
DISPLAY 0.489362 (-5535 2960);
PAINT MONO (-5535 2960);
FORCEPROP 0 LASTPIN (-5525 2900) $PN DE30
J 2
(-5535 2910);
DISPLAY 0.489362 (-5535 2910);
PAINT MONO (-5535 2910);
FORCEPROP 0 LASTPIN (-5525 2850) $PN DF31
J 2
(-5535 2860);
DISPLAY 0.489362 (-5535 2860);
PAINT MONO (-5535 2860);
FORCEPROP 0 LASTPIN (-5525 2800) $PN DG31
J 2
(-5535 2810);
DISPLAY 0.489362 (-5535 2810);
PAINT MONO (-5535 2810);
FORCEPROP 0 LASTPIN (-5525 2750) $PN DG32
J 2
(-5535 2760);
DISPLAY 0.489362 (-5535 2760);
PAINT MONO (-5535 2760);
FORCEPROP 0 LASTPIN (-5525 3250) $PN DH16
J 2
(-5535 3260);
DISPLAY 0.489362 (-5535 3260);
PAINT MONO (-5535 3260);
FORCEPROP 0 LASTPIN (-5525 3200) $PN DH15
J 2
(-5535 3210);
DISPLAY 0.489362 (-5535 3210);
PAINT MONO (-5535 3210);
FORCEPROP 0 LASTPIN (-3025 2950) $PN A14
J 0
(-3015 2960);
DISPLAY 0.489362 (-3015 2960);
PAINT MONO (-3015 2960);
FORCEPROP 0 LASTPIN (-3025 2900) $PN C14
J 0
(-3015 2910);
DISPLAY 0.489362 (-3015 2910);
PAINT MONO (-3015 2910);
FORCEPROP 0 LASTPIN (-3025 2850) $PN A13
J 0
(-3015 2860);
DISPLAY 0.489362 (-3015 2860);
PAINT MONO (-3015 2860);
FORCEPROP 0 LASTPIN (-3025 2800) $PN B16
J 0
(-3015 2810);
DISPLAY 0.489362 (-3015 2810);
PAINT MONO (-3015 2810);
FORCEPROP 0 LASTPIN (-3025 5400) $PN B63
J 0
(-3015 5410);
DISPLAY 0.489362 (-3015 5410);
PAINT MONO (-3015 5410);
FORCEPROP 0 LASTPIN (-5525 4850) $PN DJ35
J 2
(-5535 4860);
DISPLAY 0.489362 (-5535 4860);
PAINT MONO (-5535 4860);
FORCEPROP 0 LASTPIN (-3025 4850) $PN A7
J 0
(-3015 4860);
DISPLAY 0.489362 (-3015 4860);
PAINT MONO (-3015 4860);
FORCEPROP 0 LASTPIN (-3025 4900) $PN A8
J 0
(-3015 4910);
DISPLAY 0.489362 (-3015 4910);
PAINT MONO (-3015 4910);
FORCEPROP 0 LASTPIN (-3025 4700) $PN C6
J 0
(-3015 4710);
DISPLAY 0.489362 (-3015 4710);
PAINT MONO (-3015 4710);
FORCEPROP 0 LASTPIN (-3025 4750) $PN B6
J 0
(-3015 4760);
DISPLAY 0.489362 (-3015 4760);
PAINT MONO (-3015 4760);
FORCEPROP 0 LASTPIN (-3025 4550) $PN A11
J 0
(-3015 4560);
DISPLAY 0.489362 (-3015 4560);
PAINT MONO (-3015 4560);
FORCEPROP 0 LASTPIN (-3025 4600) $PN A10
J 0
(-3015 4610);
DISPLAY 0.489362 (-3015 4610);
PAINT MONO (-3015 4610);
FORCEPROP 0 LASTPIN (-3025 4400) $PN C12
J 0
(-3015 4410);
DISPLAY 0.489362 (-3015 4410);
PAINT MONO (-3015 4410);
FORCEPROP 0 LASTPIN (-3025 4450) $PN B12
J 0
(-3015 4460);
DISPLAY 0.489362 (-3015 4460);
PAINT MONO (-3015 4460);
FORCEPROP 0 LASTPIN (-3025 4250) $PN C9
J 0
(-3015 4260);
DISPLAY 0.489362 (-3015 4260);
PAINT MONO (-3015 4260);
FORCEPROP 0 LASTPIN (-3025 4300) $PN B9
J 0
(-3015 4310);
DISPLAY 0.489362 (-3015 4310);
PAINT MONO (-3015 4310);
FORCEPROP 0 LASTPIN (-3025 4100) $PN DJ42
J 0
(-3015 4110);
DISPLAY 0.489362 (-3015 4110);
PAINT MONO (-3015 4110);
FORCEPROP 0 LASTPIN (-3025 4150) $PN DJ41
J 0
(-3015 4160);
DISPLAY 0.489362 (-3015 4160);
PAINT MONO (-3015 4160);
FORCEPROP 0 LASTPIN (-3025 3950) $PN DJ44
J 0
(-3015 3960);
DISPLAY 0.489362 (-3015 3960);
PAINT MONO (-3015 3960);
FORCEPROP 0 LASTPIN (-3025 4000) $PN DJ45
J 0
(-3015 4010);
DISPLAY 0.489362 (-3015 4010);
PAINT MONO (-3015 4010);
FORCEPROP 0 LASTPIN (-3025 3800) $PN DJ54
J 0
(-3015 3810);
DISPLAY 0.489362 (-3015 3810);
PAINT MONO (-3015 3810);
FORCEPROP 0 LASTPIN (-3025 3850) $PN DJ53
J 0
(-3015 3860);
DISPLAY 0.489362 (-3015 3860);
PAINT MONO (-3015 3860);
FORCEPROP 0 LASTPIN (-3025 3650) $PN DJ47
J 0
(-3015 3660);
DISPLAY 0.489362 (-3015 3660);
PAINT MONO (-3015 3660);
FORCEPROP 0 LASTPIN (-3025 3700) $PN DJ48
J 0
(-3015 3710);
DISPLAY 0.489362 (-3015 3710);
PAINT MONO (-3015 3710);
FORCEPROP 0 LASTPIN (-3025 3500) $PN DJ50
J 0
(-3015 3510);
DISPLAY 0.489362 (-3015 3510);
PAINT MONO (-3015 3510);
FORCEPROP 0 LASTPIN (-3025 3550) $PN DJ51
J 0
(-3015 3560);
DISPLAY 0.489362 (-3015 3560);
PAINT MONO (-3015 3560);
FORCEPROP 0 LASTPIN (-5525 4000) $PN DG12
J 2
(-5535 4010);
DISPLAY 0.489362 (-5535 4010);
PAINT MONO (-5535 4010);
FORCEPROP 0 LASTPIN (-5525 3950) $PN DH12
J 2
(-5535 3960);
DISPLAY 0.489362 (-5535 3960);
PAINT MONO (-5535 3960);
FORCEPROP 0 LASTPIN (-5525 3900) $PN DJ21
J 2
(-5535 3910);
DISPLAY 0.489362 (-5535 3910);
PAINT MONO (-5535 3910);
FORCEPROP 0 LASTPIN (-5525 3850) $PN DJ20
J 2
(-5535 3860);
DISPLAY 0.489362 (-5535 3860);
PAINT MONO (-5535 3860);
FORCEPROP 0 LASTPIN (-5525 4400) $PN A71
J 2
(-5535 4410);
DISPLAY 0.489362 (-5535 4410);
PAINT MONO (-5535 4410);
FORCEPROP 0 LASTPIN (-5525 4350) $PN B71
J 2
(-5535 4360);
DISPLAY 0.489362 (-5535 4360);
PAINT MONO (-5535 4360);
FORCEPROP 0 LASTPIN (-5525 4300) $PN C7
J 2
(-5535 4310);
DISPLAY 0.489362 (-5535 4310);
PAINT MONO (-5535 4310);
FORCEPROP 0 LASTPIN (-5525 4250) $PN A5
J 2
(-5535 4260);
DISPLAY 0.489362 (-5535 4260);
PAINT MONO (-5535 4260);
FORCEPROP 0 LASTPIN (-5525 4200) $PN C72
J 2
(-5535 4210);
DISPLAY 0.489362 (-5535 4210);
PAINT MONO (-5535 4210);
FORCEPROP 0 LASTPIN (-5525 4150) $PN B72
J 2
(-5535 4160);
DISPLAY 0.489362 (-5535 4160);
PAINT MONO (-5535 4160);
FORCEPROP 0 LASTPIN (-5525 4100) $PN A4
J 2
(-5535 4110);
DISPLAY 0.489362 (-5535 4110);
PAINT MONO (-5535 4110);
FORCEPROP 0 LASTPIN (-5525 4050) $PN B4
J 2
(-5535 4060);
DISPLAY 0.489362 (-5535 4060);
PAINT MONO (-5535 4060);
FORCEPROP 0 LASTPIN (-5525 4650) $PN DJ31
J 2
(-5535 4660);
DISPLAY 0.489362 (-5535 4660);
PAINT MONO (-5535 4660);
FORCEPROP 0 LASTPIN (-3025 5300) $PN B64
J 0
(-3015 5310);
DISPLAY 0.489362 (-3015 5310);
PAINT MONO (-3015 5310);
FORCEPROP 0 LASTPIN (-3025 5150) $PN D18
J 0
(-3015 5160);
DISPLAY 0.489362 (-3015 5160);
PAINT MONO (-3015 5160);
FORCEPROP 0 LASTPIN (-3025 5100) $PN DG36
J 0
(-3015 5110);
DISPLAY 0.489362 (-3015 5110);
PAINT MONO (-3015 5110);
FORCEPROP 0 LASTPIN (-5525 5600) $PN DH7
J 2
(-5535 5610);
DISPLAY 0.489362 (-5535 5610);
PAINT MONO (-5535 5610);
FORCEPROP 0 LASTPIN (-5525 5400) $PN DJ8
J 2
(-5535 5410);
DISPLAY 0.489362 (-5535 5410);
PAINT MONO (-5535 5410);
FORCEPROP 0 LASTPIN (-3025 5600) $PN DH36
J 0
(-3015 5610);
DISPLAY 0.489362 (-3015 5610);
PAINT MONO (-3015 5610);
FORCEPROP 0 LASTPIN (-3025 5750) $PN D69
J 0
(-3015 5760);
DISPLAY 0.489362 (-3015 5760);
PAINT MONO (-3015 5760);
FORCEPROP 0 LASTPIN (-3025 6050) $PN A20
J 0
(-3015 6060);
DISPLAY 0.489362 (-3015 6060);
PAINT MONO (-3015 6060);
FORCEPROP 0 LASTPIN (-3025 6100) $PN A19
J 0
(-3015 6110);
DISPLAY 0.489362 (-3015 6110);
PAINT MONO (-3015 6110);
FORCEPROP 0 LASTPIN (-3025 5850) $PN B67
J 0
(-3015 5860);
DISPLAY 0.489362 (-3015 5860);
PAINT MONO (-3015 5860);
FORCEPROP 0 LASTPIN (-5525 5500) $PN DG10
J 2
(-5535 5510);
DISPLAY 0.489362 (-5535 5510);
PAINT MONO (-5535 5510);
FORCEPROP 0 LASTPIN (-3025 5950) $PN DH9
J 0
(-3015 5960);
DISPLAY 0.489362 (-3015 5960);
PAINT MONO (-3015 5960);
FORCEPROP 0 LASTPIN (-3025 3150) $PN B14
J 0
(-3015 3160);
DISPLAY 0.489362 (-3015 3160);
PAINT MONO (-3015 3160);
FORCEPROP 0 LASTPIN (-3025 3100) $PN D14
J 0
(-3015 3110);
DISPLAY 0.489362 (-3015 3110);
PAINT MONO (-3015 3110);
FORCEPROP 0 LASTPIN (-5525 3600) $PN D15
J 2
(-5535 3610);
DISPLAY 0.489362 (-5535 3610);
PAINT MONO (-5535 3610);
FORCEPROP 0 LASTPIN (-5525 3550) $PN B15
J 2
(-5535 3560);
DISPLAY 0.489362 (-5535 3560);
PAINT MONO (-5535 3560);
FORCEPROP 0 LASTPIN (-5525 5700) $PN DJ5
J 2
(-5535 5710);
DISPLAY 0.489362 (-5535 5710);
PAINT MONO (-5535 5710);
FORCEPROP 0 LASTPIN (-5525 5750) $PN DG4
J 2
(-5535 5760);
DISPLAY 0.489362 (-5535 5760);
PAINT MONO (-5535 5760);
FORCEPROP 0 LASTPIN (-5525 3700) $PN DJ11
J 2
(-5535 3710);
DISPLAY 0.489362 (-5535 3710);
PAINT MONO (-5535 3710);
FORCEPROP 0 LASTPIN (-5525 5550) $PN DH6
J 2
(-5535 5560);
DISPLAY 0.489362 (-5535 5560);
PAINT MONO (-5535 5560);
FORCEPROP 0 LASTPIN (-3025 5500) $PN DJ10
J 0
(-3015 5510);
DISPLAY 0.489362 (-3015 5510);
PAINT MONO (-3015 5510);
FORCEPROP 0 LASTPIN (-5525 5050) $PN DJ14
J 2
(-5535 5060);
DISPLAY 0.489362 (-5535 5060);
PAINT MONO (-5535 5060);
FORCEPROP 0 LASTPIN (-5525 5000) $PN DJ13
J 2
(-5535 5010);
DISPLAY 0.489362 (-5535 5010);
PAINT MONO (-5535 5010);
FORCEPROP 0 LASTPIN (-5525 5250) $PN DJ17
J 2
(-5535 5260);
DISPLAY 0.489362 (-5535 5260);
PAINT MONO (-5535 5260);
FORCEPROP 0 LASTPIN (-5525 5200) $PN DJ16
J 2
(-5535 5210);
DISPLAY 0.489362 (-5535 5210);
PAINT MONO (-5535 5210);
FORCEPROP 2 LAST PART_TYPE SMLF
J 0
(-5375 6100);
DISPLAY 1.021277 (-5375 6100);
FORCEPROP 1 LAST MATERIAL IO
J 0
(-5370 6283);
DISPLAY 0.489362 (-5370 6283);
PAINT SKYBLUE (-5370 6283);
FORCEPROP 2 LAST VALUE SOCKET6096_13568-001
J 0
(-5375 6000);
DISPLAY 0.489362 (-5375 6000);
PAINT SKYBLUE (-5375 6000);
FORCEPROP 1 LAST PART_NUMBER DGA^6000030
J 0
(-5370 6382);
DISPLAY 0.489362 (-5370 6382);
PAINT SKYBLUE (-5370 6382);
FORCEPROP 2 LAST CDS_LIB pure_quanta
J 0
(-4275 4450);
DISPLAY INVISIBLE (-4275 4450);
FORCEPROP 1 LAST CDS_LMAN_SYM_OUTLINE -1100,1800,1100,-1800
J 0
(-4275 4450);
DISPLAY 0.468085 (-4275 4450);
PAINT GREEN (-4275 4450);
DISPLAY INVISIBLE (-4275 4450);
FORCEPROP 1 LAST NEEDS_NO_SIZE TRUE
J 0
(-4275 4450);
DISPLAY 0.723404 (-4275 4450);
PAINT GREEN (-4275 4450);
DISPLAY INVISIBLE (-4275 4450);
FORCEPROP 1 LAST PATH I186
J 0
(-4275 4450);
DISPLAY 0.723404 (-4275 4450);
PAINT GREEN (-4275 4450);
DISPLAY INVISIBLE (-4275 4450);
FORCEADD UNIVERSAL_GND..1
(-4875 675);
FORCEPROP 3 LASTPIN (-4875 725) SIG_NAME GND\g
J 0
(-4865 735);
DISPLAY 0.659574 (-4865 735);
PAINT MONO (-4865 735);
DISPLAY INVISIBLE (-4865 735);
FORCEPROP 2 LAST CDS_LIB pure_quanta_power
J 0
(-4875 675);
DISPLAY INVISIBLE (-4875 675);
FORCEPROP 1 LAST PATH I19
J 0
(-4800 675);
DISPLAY 0.872340 (-4800 675);
PAINT AQUA (-4800 675);
DISPLAY INVISIBLE (-4800 675);
FORCEPROP 1 LAST HDL_POWER GND
J 1
(-4850 600);
DISPLAY 0.872340 (-4850 600);
PAINT GREEN (-4850 600);
DISPLAY INVISIBLE (-4850 600);
FORCEADD Q_RES..1
(-5500 1200);
FORCEPROP 1 LAST LOCATION R432
J 0
(-5550 1250);
DISPLAY 0.489362 (-5550 1250);
PAINT SKYBLUE (-5550 1250);
FORCEPROP 0 LAST $SEC 1
J 0
(-5550 1350);
DISPLAY 0.680851 (-5550 1350);
PAINT MONO (-5550 1350);
DISPLAY INVISIBLE (-5550 1350);
FORCEPROP 0 LAST CDS_SEC 1
J 0
(-5550 1350);
DISPLAY 1.021277 (-5550 1350);
DISPLAY INVISIBLE (-5550 1350);
FORCEPROP 1 LASTPIN (-5600 1200) $PN 1
J 0
(-5588 1212);
DISPLAY 0.489362 (-5588 1212);
PAINT MONO (-5588 1212);
FORCEPROP 1 LASTPIN (-5400 1200) $PN 2
J 0
(-5438 1212);
DISPLAY 0.489362 (-5438 1212);
PAINT MONO (-5438 1212);
FORCEPROP 1 LAST MATERIAL CHIP
J 0
(-5500 1050);
DISPLAY 0.489362 (-5500 1050);
PAINT SKYBLUE (-5500 1050);
FORCEPROP 1 LAST TOLERANCE 5%
J 0
(-5500 1100);
DISPLAY 0.489362 (-5500 1100);
PAINT SKYBLUE (-5500 1100);
FORCEPROP 1 LAST PACK_TYPE 0402LF
J 0
(-5250 1050);
DISPLAY 0.489362 (-5250 1050);
PAINT SKYBLUE (-5250 1050);
FORCEPROP 1 LAST WATTAGE 1/16W
J 2
(-5525 1050);
DISPLAY 0.489362 (-5525 1050);
PAINT SKYBLUE (-5525 1050);
FORCEPROP 1 LAST VALUE 10M
J 2
(-5525 1100);
DISPLAY 0.489362 (-5525 1100);
PAINT SKYBLUE (-5525 1100);
FORCEPROP 1 LAST PART_NUMBER CS61002JB23
J 0
(-5550 1300);
DISPLAY 0.489362 (-5550 1300);
PAINT SKYBLUE (-5550 1300);
FORCEPROP 2 LAST CDS_LIB pure_quanta
J 0
(-5500 1200);
DISPLAY INVISIBLE (-5500 1200);
FORCEPROP 1 LAST PATH I20
J 0
(-5550 1350);
DISPLAY 0.978723 (-5550 1350);
PAINT WHITE (-5550 1350);
DISPLAY INVISIBLE (-5550 1350);
FORCEADD OFFPAGE..2
(-775 6050);
FORCEPROP 2 LAST $XR0 55 
J 0
(-586 6050);
DISPLAY 0.638298 (-586 6050);
PAINT MONO (-586 6050);
FORCEPROP 2 LAST CDS_LIB standard
J 0
(-775 6050);
DISPLAY INVISIBLE (-775 6050);
FORCEPROP 1 LAST OFFPAGE TRUE
J 0
(-450 5925);
DISPLAY 0.872340 (-450 5925);
PAINT GREEN (-450 5925);
DISPLAY INVISIBLE (-450 5925);
FORCEPROP 1 LAST COMMENT_BODY TRUE
J 0
(-820 5955);
DISPLAY 0.872340 (-820 5955);
PAINT GREEN (-820 5955);
DISPLAY INVISIBLE (-820 5955);
FORCEPROP 2 LAST PATH I203
J 0
(-575 6100);
DISPLAY 1.021277 (-575 6100);
DISPLAY INVISIBLE (-575 6100);
FORCEADD OFFPAGE..2
(-775 6100);
FORCEPROP 2 LAST $XR0 55 
J 0
(-586 6100);
DISPLAY 0.638298 (-586 6100);
PAINT MONO (-586 6100);
FORCEPROP 2 LAST CDS_LIB standard
J 0
(-775 6100);
DISPLAY INVISIBLE (-775 6100);
FORCEPROP 1 LAST OFFPAGE TRUE
J 0
(-450 5975);
DISPLAY 0.872340 (-450 5975);
PAINT GREEN (-450 5975);
DISPLAY INVISIBLE (-450 5975);
FORCEPROP 1 LAST COMMENT_BODY TRUE
J 0
(-820 6005);
DISPLAY 0.872340 (-820 6005);
PAINT GREEN (-820 6005);
DISPLAY INVISIBLE (-820 6005);
FORCEPROP 2 LAST PATH I204
J 0
(-575 6150);
DISPLAY 1.021277 (-575 6150);
DISPLAY INVISIBLE (-575 6150);
FORCEADD Q_RES..1
(-1725 6100);
FORCEPROP 1 LAST LOCATION R435
J 0
(-2075 6100);
DISPLAY 0.489362 (-2075 6100);
PAINT SKYBLUE (-2075 6100);
FORCEPROP 0 LAST $SEC 1
J 0
(-2000 6150);
DISPLAY 0.680851 (-2000 6150);
PAINT MONO (-2000 6150);
DISPLAY INVISIBLE (-2000 6150);
FORCEPROP 0 LAST CDS_SEC 1
J 0
(-2000 6150);
DISPLAY 1.021277 (-2000 6150);
DISPLAY INVISIBLE (-2000 6150);
FORCEPROP 1 LASTPIN (-1825 6100) $PN 1
J 0
(-1813 6112);
DISPLAY 0.489362 (-1813 6112);
PAINT MONO (-1813 6112);
FORCEPROP 1 LASTPIN (-1625 6100) $PN 2
J 0
(-1663 6112);
DISPLAY 0.489362 (-1663 6112);
PAINT MONO (-1663 6112);
FORCEPROP 1 LAST VALUE 0
J 2
(-1825 6100);
DISPLAY 0.489362 (-1825 6100);
PAINT SKYBLUE (-1825 6100);
FORCEPROP 2 LAST CDS_LIB pure_quanta
J 0
(-1725 6100);
DISPLAY INVISIBLE (-1725 6100);
FORCEPROP 1 LAST PATH I206
J 0
(-1775 6250);
DISPLAY 0.978723 (-1775 6250);
PAINT WHITE (-1775 6250);
DISPLAY INVISIBLE (-1775 6250);
FORCEPROP 1 LAST WATTAGE 1/16W
J 2
(-1325 6025);
DISPLAY 0.489362 (-1325 6025);
PAINT SKYBLUE (-1325 6025);
DISPLAY INVISIBLE (-1325 6025);
FORCEPROP 1 LAST MATERIAL CHIP
J 0
(-1300 6025);
DISPLAY 0.489362 (-1300 6025);
PAINT SKYBLUE (-1300 6025);
DISPLAY INVISIBLE (-1300 6025);
FORCEPROP 1 LAST TOLERANCE 5%
J 0
(-1750 6025);
DISPLAY 0.489362 (-1750 6025);
PAINT SKYBLUE (-1750 6025);
DISPLAY INVISIBLE (-1750 6025);
FORCEPROP 1 LAST PART_NUMBER CS00002JB38
J 0
(-1700 6150);
DISPLAY 0.489362 (-1700 6150);
PAINT SKYBLUE (-1700 6150);
DISPLAY INVISIBLE (-1700 6150);
FORCEPROP 1 LAST PACK_TYPE 0402LF
J 0
(-1675 6025);
DISPLAY 0.489362 (-1675 6025);
PAINT SKYBLUE (-1675 6025);
DISPLAY INVISIBLE (-1675 6025);
FORCEADD Q_RES..1
(-1725 6050);
FORCEPROP 1 LAST LOCATION R436
J 0
(-2075 6050);
DISPLAY 0.489362 (-2075 6050);
PAINT SKYBLUE (-2075 6050);
FORCEPROP 0 LAST $SEC 1
J 0
(-2000 6100);
DISPLAY 0.680851 (-2000 6100);
PAINT MONO (-2000 6100);
DISPLAY INVISIBLE (-2000 6100);
FORCEPROP 0 LAST CDS_SEC 1
J 0
(-2000 6100);
DISPLAY 1.021277 (-2000 6100);
DISPLAY INVISIBLE (-2000 6100);
FORCEPROP 1 LASTPIN (-1825 6050) $PN 1
J 0
(-1813 6062);
DISPLAY 0.489362 (-1813 6062);
PAINT MONO (-1813 6062);
FORCEPROP 1 LASTPIN (-1625 6050) $PN 2
J 0
(-1663 6062);
DISPLAY 0.489362 (-1663 6062);
PAINT MONO (-1663 6062);
FORCEPROP 1 LAST VALUE 0
J 2
(-1825 6050);
DISPLAY 0.489362 (-1825 6050);
PAINT SKYBLUE (-1825 6050);
FORCEPROP 2 LAST CDS_LIB pure_quanta
J 0
(-1725 6050);
DISPLAY INVISIBLE (-1725 6050);
FORCEPROP 1 LAST PATH I207
J 0
(-1775 6200);
DISPLAY 0.978723 (-1775 6200);
PAINT WHITE (-1775 6200);
DISPLAY INVISIBLE (-1775 6200);
FORCEPROP 1 LAST WATTAGE 1/16W
J 2
(-1325 5975);
DISPLAY 0.489362 (-1325 5975);
PAINT SKYBLUE (-1325 5975);
DISPLAY INVISIBLE (-1325 5975);
FORCEPROP 1 LAST MATERIAL CHIP
J 0
(-1300 5975);
DISPLAY 0.489362 (-1300 5975);
PAINT SKYBLUE (-1300 5975);
DISPLAY INVISIBLE (-1300 5975);
FORCEPROP 1 LAST TOLERANCE 5%
J 0
(-1750 5975);
DISPLAY 0.489362 (-1750 5975);
PAINT SKYBLUE (-1750 5975);
DISPLAY INVISIBLE (-1750 5975);
FORCEPROP 1 LAST PART_NUMBER CS00002JB38
J 0
(-1700 6100);
DISPLAY 0.489362 (-1700 6100);
PAINT SKYBLUE (-1700 6100);
DISPLAY INVISIBLE (-1700 6100);
FORCEPROP 1 LAST PACK_TYPE 0402LF
J 0
(-1675 5975);
DISPLAY 0.489362 (-1675 5975);
PAINT SKYBLUE (-1675 5975);
DISPLAY INVISIBLE (-1675 5975);
FORCEADD OFFPAGE..3
(-1775 5850);
FORCEPROP 2 LAST $XR2 84 
J 0
(-1381 5850);
DISPLAY 0.638298 (-1381 5850);
PAINT MONO (-1381 5850);
FORCEPROP 2 LAST $XR1 80 
J 0
(-1471 5850);
DISPLAY 0.638298 (-1471 5850);
PAINT MONO (-1471 5850);
FORCEPROP 2 LAST $XR0 28 
J 0
(-1561 5850);
DISPLAY 0.638298 (-1561 5850);
PAINT MONO (-1561 5850);
FORCEPROP 2 LAST CDS_LIB standard
J 2
(-1775 5850);
DISPLAY INVISIBLE (-1775 5850);
FORCEPROP 1 LAST OFFPAGE TRUE
J 0
(-1450 5725);
DISPLAY 0.872340 (-1450 5725);
PAINT GREEN (-1450 5725);
DISPLAY INVISIBLE (-1450 5725);
FORCEPROP 1 LAST COMMENT_BODY TRUE
J 0
(-1825 5750);
DISPLAY 0.872340 (-1825 5750);
PAINT PEACH (-1825 5750);
DISPLAY INVISIBLE (-1825 5750);
FORCEPROP 2 LAST PATH I208
J 0
(-1150 5900);
DISPLAY 1.021277 (-1150 5900);
DISPLAY INVISIBLE (-1150 5900);
FORCEADD OFFPAGE..3
(-1775 5750);
FORCEPROP 2 LAST $XR3 84 
J 0
(-1291 5750);
DISPLAY 0.638298 (-1291 5750);
PAINT MONO (-1291 5750);
FORCEPROP 2 LAST $XR2 77 
J 0
(-1381 5750);
DISPLAY 0.638298 (-1381 5750);
PAINT MONO (-1381 5750);
FORCEPROP 2 LAST $XR1 80 
J 0
(-1471 5750);
DISPLAY 0.638298 (-1471 5750);
PAINT MONO (-1471 5750);
FORCEPROP 2 LAST $XR0 28 
J 0
(-1561 5750);
DISPLAY 0.638298 (-1561 5750);
PAINT MONO (-1561 5750);
FORCEPROP 2 LAST CDS_LIB standard
J 2
(-1775 5750);
DISPLAY INVISIBLE (-1775 5750);
FORCEPROP 1 LAST OFFPAGE TRUE
J 0
(-1450 5625);
DISPLAY 0.872340 (-1450 5625);
PAINT GREEN (-1450 5625);
DISPLAY INVISIBLE (-1450 5625);
FORCEPROP 1 LAST COMMENT_BODY TRUE
J 0
(-1825 5650);
DISPLAY 0.872340 (-1825 5650);
PAINT PEACH (-1825 5650);
DISPLAY INVISIBLE (-1825 5650);
FORCEPROP 2 LAST PATH I209
J 0
(-1075 5800);
DISPLAY 1.021277 (-1075 5800);
DISPLAY INVISIBLE (-1075 5800);
FORCEADD OFFPAGE..2
(-4475 2250);
FORCEPROP 2 LAST $XR0 28 
J 0
(-4286 2250);
DISPLAY 0.638298 (-4286 2250);
PAINT MONO (-4286 2250);
FORCEPROP 2 LAST CDS_LIB standard
J 0
(-4475 2250);
DISPLAY INVISIBLE (-4475 2250);
FORCEPROP 1 LAST OFFPAGE TRUE
J 0
(-4150 2125);
DISPLAY 0.872340 (-4150 2125);
PAINT GREEN (-4150 2125);
DISPLAY INVISIBLE (-4150 2125);
FORCEPROP 1 LAST COMMENT_BODY TRUE
J 0
(-4520 2155);
DISPLAY 0.872340 (-4520 2155);
PAINT GREEN (-4520 2155);
DISPLAY INVISIBLE (-4520 2155);
FORCEPROP 2 LAST PATH I21
J 0
(-4300 2325);
DISPLAY 1.021277 (-4300 2325);
DISPLAY INVISIBLE (-4300 2325);
FORCEADD OFFPAGE..2
(-1350 5600);
FORCEPROP 2 LAST $XR1 80 
J 0
(-1071 5600);
DISPLAY 0.638298 (-1071 5600);
PAINT MONO (-1071 5600);
FORCEPROP 2 LAST $XR0 55 
J 0
(-1161 5600);
DISPLAY 0.638298 (-1161 5600);
PAINT MONO (-1161 5600);
FORCEPROP 2 LAST CDS_LIB standard
J 0
(-1350 5600);
DISPLAY INVISIBLE (-1350 5600);
FORCEPROP 1 LAST OFFPAGE TRUE
J 0
(-1025 5475);
DISPLAY 0.872340 (-1025 5475);
PAINT GREEN (-1025 5475);
DISPLAY INVISIBLE (-1025 5475);
FORCEPROP 1 LAST COMMENT_BODY TRUE
J 0
(-1395 5505);
DISPLAY 0.872340 (-1395 5505);
PAINT GREEN (-1395 5505);
DISPLAY INVISIBLE (-1395 5505);
FORCEPROP 2 LAST PATH I210
J 0
(-1050 5650);
DISPLAY 1.021277 (-1050 5650);
DISPLAY INVISIBLE (-1050 5650);
FORCEADD OFFPAGE..2
(-4475 2200);
FORCEPROP 2 LAST $XR0 28 
J 0
(-4286 2200);
DISPLAY 0.638298 (-4286 2200);
PAINT MONO (-4286 2200);
FORCEPROP 2 LAST CDS_LIB standard
J 0
(-4475 2200);
DISPLAY INVISIBLE (-4475 2200);
FORCEPROP 1 LAST OFFPAGE TRUE
J 0
(-4150 2075);
DISPLAY 0.872340 (-4150 2075);
PAINT GREEN (-4150 2075);
DISPLAY INVISIBLE (-4150 2075);
FORCEPROP 1 LAST COMMENT_BODY TRUE
J 0
(-4520 2105);
DISPLAY 0.872340 (-4520 2105);
PAINT GREEN (-4520 2105);
DISPLAY INVISIBLE (-4520 2105);
FORCEPROP 2 LAST PATH I22
J 0
(-4300 2275);
DISPLAY 1.021277 (-4300 2275);
DISPLAY INVISIBLE (-4300 2275);
FORCEADD OFFPAGE..2
(-2175 5950);
FORCEPROP 2 LAST $XR1 55 
J 0
(-1896 5950);
DISPLAY 0.638298 (-1896 5950);
PAINT MONO (-1896 5950);
FORCEPROP 2 LAST $XR0 75 
J 0
(-1986 5950);
DISPLAY 0.638298 (-1986 5950);
PAINT MONO (-1986 5950);
FORCEPROP 2 LAST CDS_LIB standard
J 0
(-2175 5950);
DISPLAY INVISIBLE (-2175 5950);
FORCEPROP 1 LAST OFFPAGE TRUE
J 0
(-1850 5825);
DISPLAY 0.872340 (-1850 5825);
PAINT GREEN (-1850 5825);
DISPLAY INVISIBLE (-1850 5825);
FORCEPROP 1 LAST COMMENT_BODY TRUE
J 0
(-2220 5855);
DISPLAY 0.872340 (-2220 5855);
PAINT GREEN (-2220 5855);
DISPLAY INVISIBLE (-2220 5855);
FORCEPROP 2 LAST PATH I223
J 0
(-1850 6000);
DISPLAY 1.021277 (-1850 6000);
DISPLAY INVISIBLE (-1850 6000);
FORCEADD Q_RES..1
(-2100 5600);
FORCEPROP 1 LAST LOCATION R434
J 0
(-2375 5600);
DISPLAY 0.489362 (-2375 5600);
PAINT SKYBLUE (-2375 5600);
FORCEPROP 0 LAST $SEC 1
J 0
(-2275 5650);
DISPLAY 0.680851 (-2275 5650);
PAINT MONO (-2275 5650);
DISPLAY INVISIBLE (-2275 5650);
FORCEPROP 0 LAST CDS_SEC 1
J 0
(-2275 5650);
DISPLAY 1.021277 (-2275 5650);
DISPLAY INVISIBLE (-2275 5650);
FORCEPROP 1 LASTPIN (-2200 5600) $PN 1
J 0
(-2188 5612);
DISPLAY 0.489362 (-2188 5612);
PAINT MONO (-2188 5612);
FORCEPROP 1 LASTPIN (-2000 5600) $PN 2
J 0
(-2038 5612);
DISPLAY 0.489362 (-2038 5612);
PAINT MONO (-2038 5612);
FORCEPROP 1 LAST VALUE 33
J 2
(-1925 5600);
DISPLAY 0.489362 (-1925 5600);
PAINT SKYBLUE (-1925 5600);
FORCEPROP 2 LAST CDS_LIB pure_quanta
J 0
(-2100 5600);
DISPLAY INVISIBLE (-2100 5600);
FORCEPROP 1 LAST PATH I224
J 0
(-2150 5750);
DISPLAY 0.978723 (-2150 5750);
PAINT WHITE (-2150 5750);
DISPLAY INVISIBLE (-2150 5750);
FORCEPROP 1 LAST WATTAGE 1/16W
J 2
(-1700 5525);
DISPLAY 0.489362 (-1700 5525);
PAINT SKYBLUE (-1700 5525);
DISPLAY INVISIBLE (-1700 5525);
FORCEPROP 1 LAST MATERIAL CHIP
J 0
(-1675 5525);
DISPLAY 0.489362 (-1675 5525);
PAINT SKYBLUE (-1675 5525);
DISPLAY INVISIBLE (-1675 5525);
FORCEPROP 1 LAST TOLERANCE 5%
J 0
(-2125 5525);
DISPLAY 0.489362 (-2125 5525);
PAINT SKYBLUE (-2125 5525);
DISPLAY INVISIBLE (-2125 5525);
FORCEPROP 1 LAST PART_NUMBER CS03302JB29
J 0
(-2075 5650);
DISPLAY 0.489362 (-2075 5650);
PAINT SKYBLUE (-2075 5650);
DISPLAY INVISIBLE (-2075 5650);
FORCEPROP 1 LAST PACK_TYPE 0402LF
J 0
(-2050 5525);
DISPLAY 0.489362 (-2050 5525);
PAINT SKYBLUE (-2050 5525);
DISPLAY INVISIBLE (-2050 5525);
FORCEADD OFFPAGE..1
R 2
(-2200 5400);
FORCEPROP 2 LAST $XR1 80 
J 0
(-1924 5400);
DISPLAY 0.638298 (-1924 5400);
PAINT MONO (-1924 5400);
FORCEPROP 2 LAST $XR0 28 
J 0
(-2014 5400);
DISPLAY 0.638298 (-2014 5400);
PAINT MONO (-2014 5400);
FORCEPROP 2 LAST CDS_LIB standard
J 0
(-2200 5400);
DISPLAY INVISIBLE (-2200 5400);
FORCEPROP 1 LAST OFFPAGE TRUE
J 2
(-2525 5275);
DISPLAY 0.872340 (-2525 5275);
PAINT GREEN (-2525 5275);
DISPLAY INVISIBLE (-2525 5275);
FORCEPROP 1 LAST COMMENT_BODY TRUE
J 2
(-2325 5300);
DISPLAY 0.872340 (-2325 5300);
PAINT GREEN (-2325 5300);
DISPLAY INVISIBLE (-2325 5300);
FORCEPROP 2 LAST PATH I225
J 0
(-1900 5450);
DISPLAY 1.021277 (-1900 5450);
DISPLAY INVISIBLE (-1900 5450);
FORCEADD OFFPAGE..2
(-2200 5300);
FORCEPROP 2 LAST $XR1 80 
J 0
(-1921 5300);
DISPLAY 0.638298 (-1921 5300);
PAINT MONO (-1921 5300);
FORCEPROP 2 LAST $XR0 28 
J 0
(-2011 5300);
DISPLAY 0.638298 (-2011 5300);
PAINT MONO (-2011 5300);
FORCEPROP 2 LAST CDS_LIB standard
J 0
(-2200 5300);
DISPLAY INVISIBLE (-2200 5300);
FORCEPROP 1 LAST OFFPAGE TRUE
J 0
(-1875 5175);
DISPLAY 0.872340 (-1875 5175);
PAINT GREEN (-1875 5175);
DISPLAY INVISIBLE (-1875 5175);
FORCEPROP 1 LAST COMMENT_BODY TRUE
J 0
(-2245 5205);
DISPLAY 0.872340 (-2245 5205);
PAINT GREEN (-2245 5205);
DISPLAY INVISIBLE (-2245 5205);
FORCEPROP 2 LAST PATH I226
J 0
(-1900 5350);
DISPLAY 1.021277 (-1900 5350);
DISPLAY INVISIBLE (-1900 5350);
FORCEADD OFFPAGE..2
(-2175 5150);
FORCEPROP 2 LAST $XR1 82 
J 0
(-1896 5150);
DISPLAY 0.638298 (-1896 5150);
PAINT MONO (-1896 5150);
FORCEPROP 2 LAST $XR0 80 
J 0
(-1986 5150);
DISPLAY 0.638298 (-1986 5150);
PAINT MONO (-1986 5150);
FORCEPROP 2 LAST CDS_LIB standard
J 0
(-2175 5150);
DISPLAY INVISIBLE (-2175 5150);
FORCEPROP 1 LAST OFFPAGE TRUE
J 0
(-1850 5025);
DISPLAY 0.872340 (-1850 5025);
PAINT GREEN (-1850 5025);
DISPLAY INVISIBLE (-1850 5025);
FORCEPROP 1 LAST COMMENT_BODY TRUE
J 0
(-2220 5055);
DISPLAY 0.872340 (-2220 5055);
PAINT GREEN (-2220 5055);
DISPLAY INVISIBLE (-2220 5055);
FORCEPROP 2 LAST PATH I227
J 0
(-1875 5200);
DISPLAY 1.021277 (-1875 5200);
DISPLAY INVISIBLE (-1875 5200);
FORCEADD OFFPAGE..2
(-2175 5100);
FORCEPROP 2 LAST $XR1 82 
J 0
(-1896 5100);
DISPLAY 0.638298 (-1896 5100);
PAINT MONO (-1896 5100);
FORCEPROP 2 LAST $XR0 80 
J 0
(-1986 5100);
DISPLAY 0.638298 (-1986 5100);
PAINT MONO (-1986 5100);
FORCEPROP 2 LAST CDS_LIB standard
J 0
(-2175 5100);
DISPLAY INVISIBLE (-2175 5100);
FORCEPROP 1 LAST OFFPAGE TRUE
J 0
(-1850 4975);
DISPLAY 0.872340 (-1850 4975);
PAINT GREEN (-1850 4975);
DISPLAY INVISIBLE (-1850 4975);
FORCEPROP 1 LAST COMMENT_BODY TRUE
J 0
(-2220 5005);
DISPLAY 0.872340 (-2220 5005);
PAINT GREEN (-2220 5005);
DISPLAY INVISIBLE (-2220 5005);
FORCEPROP 2 LAST PATH I229
J 0
(-1875 5150);
DISPLAY 1.021277 (-1875 5150);
DISPLAY INVISIBLE (-1875 5150);
FORCEADD OFFPAGE..1
(-6300 5250);
FORCEPROP 2 LAST $XR0 28 
J 0
(-6521 5250);
DISPLAY 0.638298 (-6521 5250);
PAINT MONO (-6521 5250);
FORCEPROP 2 LAST CDS_LIB standard
J 0
(-6300 5250);
DISPLAY INVISIBLE (-6300 5250);
FORCEPROP 1 LAST OFFPAGE TRUE
J 0
(-5975 5125);
DISPLAY 0.872340 (-5975 5125);
PAINT GREEN (-5975 5125);
DISPLAY INVISIBLE (-5975 5125);
FORCEPROP 1 LAST COMMENT_BODY TRUE
J 0
(-6175 5150);
DISPLAY 0.872340 (-6175 5150);
PAINT GREEN (-6175 5150);
DISPLAY INVISIBLE (-6175 5150);
FORCEPROP 2 LAST PATH I23
J 0
(-6250 5325);
DISPLAY 1.021277 (-6250 5325);
DISPLAY INVISIBLE (-6250 5325);
FORCEADD OFFPAGE..1
(-6300 5200);
FORCEPROP 2 LAST $XR0 28 
J 0
(-6521 5200);
DISPLAY 0.638298 (-6521 5200);
PAINT MONO (-6521 5200);
FORCEPROP 2 LAST CDS_LIB standard
J 0
(-6300 5200);
DISPLAY INVISIBLE (-6300 5200);
FORCEPROP 1 LAST OFFPAGE TRUE
J 0
(-5975 5075);
DISPLAY 0.872340 (-5975 5075);
PAINT GREEN (-5975 5075);
DISPLAY INVISIBLE (-5975 5075);
FORCEPROP 1 LAST COMMENT_BODY TRUE
J 0
(-6175 5100);
DISPLAY 0.872340 (-6175 5100);
PAINT GREEN (-6175 5100);
DISPLAY INVISIBLE (-6175 5100);
FORCEPROP 2 LAST PATH I24
J 0
(-6250 5275);
DISPLAY 1.021277 (-6250 5275);
DISPLAY INVISIBLE (-6250 5275);
FORCEADD OFFPAGE..1
R 2
(-2050 3150);
FORCEPROP 2 LAST $XR0 138 
J 0
(-1864 3150);
DISPLAY 0.638298 (-1864 3150);
PAINT MONO (-1864 3150);
FORCEPROP 2 LAST CDS_LIB standard
J 0
(-2050 3150);
DISPLAY INVISIBLE (-2050 3150);
FORCEPROP 1 LAST OFFPAGE TRUE
J 2
(-2375 3025);
DISPLAY 0.872340 (-2375 3025);
PAINT GREEN (-2375 3025);
DISPLAY INVISIBLE (-2375 3025);
FORCEPROP 1 LAST COMMENT_BODY TRUE
J 2
(-2175 3050);
DISPLAY 0.872340 (-2175 3050);
PAINT GREEN (-2175 3050);
DISPLAY INVISIBLE (-2175 3050);
FORCEPROP 2 LAST PATH I283
J 0
(-1875 3225);
DISPLAY 1.021277 (-1875 3225);
DISPLAY INVISIBLE (-1875 3225);
FORCEADD OFFPAGE..3
(-2050 3100);
FORCEPROP 2 LAST $XR0 138 
J 0
(-1836 3100);
DISPLAY 0.638298 (-1836 3100);
PAINT MONO (-1836 3100);
FORCEPROP 2 LAST CDS_LIB standard
J 0
(-2050 3100);
DISPLAY INVISIBLE (-2050 3100);
FORCEPROP 1 LAST OFFPAGE TRUE
J 0
(-1725 2975);
DISPLAY 0.872340 (-1725 2975);
PAINT GREEN (-1725 2975);
DISPLAY INVISIBLE (-1725 2975);
FORCEPROP 1 LAST COMMENT_BODY TRUE
J 0
(-2100 3000);
DISPLAY 0.872340 (-2100 3000);
PAINT PEACH (-2100 3000);
DISPLAY INVISIBLE (-2100 3000);
FORCEPROP 2 LAST PATH I284
J 0
(-1850 3175);
DISPLAY 1.021277 (-1850 3175);
DISPLAY INVISIBLE (-1850 3175);
FORCEADD Q_RES..1
R 2
(-6775 4100);
FORCEPROP 1 LAST LOCATION R29
J 0
(-6525 4100);
DISPLAY 0.489362 (-6525 4100);
PAINT SKYBLUE (-6525 4100);
FORCEPROP 0 LAST $SEC 1
J 0
(-6475 4125);
DISPLAY 0.680851 (-6475 4125);
PAINT MONO (-6475 4125);
DISPLAY INVISIBLE (-6475 4125);
FORCEPROP 0 LAST CDS_SEC 1
J 0
(-6475 4125);
DISPLAY 1.021277 (-6475 4125);
DISPLAY INVISIBLE (-6475 4125);
FORCEPROP 1 LASTPIN (-6675 4100) $PN 1
J 2
(-6687 4112);
DISPLAY 0.489362 (-6687 4112);
PAINT MONO (-6687 4112);
FORCEPROP 1 LASTPIN (-6875 4100) $PN 2
J 2
(-6837 4112);
DISPLAY 0.489362 (-6837 4112);
PAINT MONO (-6837 4112);
FORCEPROP 1 LAST VALUE 0
J 0
(-6675 4100);
DISPLAY 0.489362 (-6675 4100);
PAINT SKYBLUE (-6675 4100);
FORCEPROP 2 LAST CDS_LIB pure_quanta
J 0
(-6775 4100);
DISPLAY INVISIBLE (-6775 4100);
FORCEPROP 1 LAST PATH I285
J 2
(-6725 4250);
DISPLAY 0.978723 (-6725 4250);
PAINT WHITE (-6725 4250);
DISPLAY INVISIBLE (-6725 4250);
FORCEPROP 1 LAST WATTAGE 1/16W
J 0
(-7175 4025);
DISPLAY 0.489362 (-7175 4025);
PAINT SKYBLUE (-7175 4025);
DISPLAY INVISIBLE (-7175 4025);
FORCEPROP 1 LAST MATERIAL CHIP
J 2
(-7200 4025);
DISPLAY 0.489362 (-7200 4025);
PAINT SKYBLUE (-7200 4025);
DISPLAY INVISIBLE (-7200 4025);
FORCEPROP 1 LAST TOLERANCE 5%
J 2
(-6750 4025);
DISPLAY 0.489362 (-6750 4025);
PAINT SKYBLUE (-6750 4025);
DISPLAY INVISIBLE (-6750 4025);
FORCEPROP 1 LAST PART_NUMBER CS00002JB38
J 2
(-6800 4150);
DISPLAY 0.489362 (-6800 4150);
PAINT SKYBLUE (-6800 4150);
DISPLAY INVISIBLE (-6800 4150);
FORCEPROP 1 LAST PACK_TYPE 0402LF
J 2
(-6825 4025);
DISPLAY 0.489362 (-6825 4025);
PAINT SKYBLUE (-6825 4025);
DISPLAY INVISIBLE (-6825 4025);
FORCEADD Q_RES..1
R 2
(-6775 4050);
FORCEPROP 1 LAST LOCATION R30
J 0
(-6525 4050);
DISPLAY 0.489362 (-6525 4050);
PAINT SKYBLUE (-6525 4050);
FORCEPROP 0 LAST $SEC 1
J 0
(-6475 4075);
DISPLAY 0.680851 (-6475 4075);
PAINT MONO (-6475 4075);
DISPLAY INVISIBLE (-6475 4075);
FORCEPROP 0 LAST CDS_SEC 1
J 0
(-6475 4075);
DISPLAY 1.021277 (-6475 4075);
DISPLAY INVISIBLE (-6475 4075);
FORCEPROP 1 LASTPIN (-6675 4050) $PN 1
J 2
(-6687 4062);
DISPLAY 0.489362 (-6687 4062);
PAINT MONO (-6687 4062);
FORCEPROP 1 LASTPIN (-6875 4050) $PN 2
J 2
(-6837 4062);
DISPLAY 0.489362 (-6837 4062);
PAINT MONO (-6837 4062);
FORCEPROP 1 LAST VALUE 0
J 0
(-6675 4050);
DISPLAY 0.489362 (-6675 4050);
PAINT SKYBLUE (-6675 4050);
FORCEPROP 2 LAST CDS_LIB pure_quanta
J 0
(-6775 4050);
DISPLAY INVISIBLE (-6775 4050);
FORCEPROP 1 LAST PATH I286
J 2
(-6725 4200);
DISPLAY 0.978723 (-6725 4200);
PAINT WHITE (-6725 4200);
DISPLAY INVISIBLE (-6725 4200);
FORCEPROP 1 LAST WATTAGE 1/16W
J 0
(-7175 3975);
DISPLAY 0.489362 (-7175 3975);
PAINT SKYBLUE (-7175 3975);
DISPLAY INVISIBLE (-7175 3975);
FORCEPROP 1 LAST MATERIAL CHIP
J 2
(-7200 3975);
DISPLAY 0.489362 (-7200 3975);
PAINT SKYBLUE (-7200 3975);
DISPLAY INVISIBLE (-7200 3975);
FORCEPROP 1 LAST TOLERANCE 5%
J 2
(-6750 3975);
DISPLAY 0.489362 (-6750 3975);
PAINT SKYBLUE (-6750 3975);
DISPLAY INVISIBLE (-6750 3975);
FORCEPROP 1 LAST PART_NUMBER CS00002JB38
J 2
(-6800 4100);
DISPLAY 0.489362 (-6800 4100);
PAINT SKYBLUE (-6800 4100);
DISPLAY INVISIBLE (-6800 4100);
FORCEPROP 1 LAST PACK_TYPE 0402LF
J 2
(-6825 3975);
DISPLAY 0.489362 (-6825 3975);
PAINT SKYBLUE (-6825 3975);
DISPLAY INVISIBLE (-6825 3975);
FORCEADD OFFPAGE..2
R 2
(-7825 4100);
FORCEPROP 2 LAST $XR0 111 
J 0
(-8110 4100);
DISPLAY 0.638298 (-8110 4100);
PAINT MONO (-8110 4100);
FORCEPROP 2 LAST PATH I287
J 0
(-7775 4175);
DISPLAY 1.021277 (-7775 4175);
DISPLAY INVISIBLE (-7775 4175);
FORCEPROP 1 LAST COMMENT_BODY TRUE
J 2
(-7780 4005);
DISPLAY 0.872340 (-7780 4005);
PAINT GREEN (-7780 4005);
DISPLAY INVISIBLE (-7780 4005);
FORCEPROP 1 LAST OFFPAGE TRUE
J 2
(-8150 3975);
DISPLAY 0.872340 (-8150 3975);
PAINT GREEN (-8150 3975);
DISPLAY INVISIBLE (-8150 3975);
FORCEPROP 2 LAST CDS_LIB standard
J 0
(-7825 4100);
DISPLAY INVISIBLE (-7825 4100);
FORCEADD OFFPAGE..3
R 2
(-7825 4050);
FORCEPROP 2 LAST $XR0 111 
J 0
(-8135 4050);
DISPLAY 0.638298 (-8135 4050);
PAINT MONO (-8135 4050);
FORCEPROP 2 LAST PATH I288
J 0
(-7775 4125);
DISPLAY 1.021277 (-7775 4125);
DISPLAY INVISIBLE (-7775 4125);
FORCEPROP 1 LAST COMMENT_BODY TRUE
J 2
(-7775 3950);
DISPLAY 0.872340 (-7775 3950);
PAINT PEACH (-7775 3950);
DISPLAY INVISIBLE (-7775 3950);
FORCEPROP 1 LAST OFFPAGE TRUE
J 2
(-8150 3925);
DISPLAY 0.872340 (-8150 3925);
PAINT GREEN (-8150 3925);
DISPLAY INVISIBLE (-8150 3925);
FORCEPROP 2 LAST CDS_LIB standard
J 0
(-7825 4050);
DISPLAY INVISIBLE (-7825 4050);
FORCEADD OFFPAGE..3
R 2
(-7825 4150);
FORCEPROP 2 LAST $XR0 111 
J 0
(-8135 4150);
DISPLAY 0.638298 (-8135 4150);
PAINT MONO (-8135 4150);
FORCEPROP 2 LAST PATH I289
J 0
(-7775 4225);
DISPLAY 1.021277 (-7775 4225);
DISPLAY INVISIBLE (-7775 4225);
FORCEPROP 1 LAST COMMENT_BODY TRUE
J 2
(-7775 4050);
DISPLAY 0.872340 (-7775 4050);
PAINT PEACH (-7775 4050);
DISPLAY INVISIBLE (-7775 4050);
FORCEPROP 1 LAST OFFPAGE TRUE
J 2
(-8150 4025);
DISPLAY 0.872340 (-8150 4025);
PAINT GREEN (-8150 4025);
DISPLAY INVISIBLE (-8150 4025);
FORCEPROP 2 LAST CDS_LIB standard
J 0
(-7825 4150);
DISPLAY INVISIBLE (-7825 4150);
FORCEADD OFFPAGE..2
R 2
(-7825 4200);
FORCEPROP 2 LAST $XR0 111 
J 0
(-8080 4200);
DISPLAY 0.638298 (-8080 4200);
PAINT MONO (-8080 4200);
FORCEPROP 2 LAST PATH I290
J 0
(-7775 4275);
DISPLAY 1.021277 (-7775 4275);
DISPLAY INVISIBLE (-7775 4275);
FORCEPROP 1 LAST COMMENT_BODY TRUE
J 2
(-7780 4105);
DISPLAY 0.872340 (-7780 4105);
PAINT GREEN (-7780 4105);
DISPLAY INVISIBLE (-7780 4105);
FORCEPROP 1 LAST OFFPAGE TRUE
J 2
(-8150 4075);
DISPLAY 0.872340 (-8150 4075);
PAINT GREEN (-8150 4075);
DISPLAY INVISIBLE (-8150 4075);
FORCEPROP 2 LAST CDS_LIB standard
J 0
(-7825 4200);
DISPLAY INVISIBLE (-7825 4200);
FORCEADD Q_RES..1
R 2
(-6775 4150);
FORCEPROP 1 LAST LOCATION R28
J 0
(-6525 4150);
DISPLAY 0.489362 (-6525 4150);
PAINT SKYBLUE (-6525 4150);
FORCEPROP 0 LAST $SEC 1
J 0
(-6475 4175);
DISPLAY 0.680851 (-6475 4175);
PAINT MONO (-6475 4175);
DISPLAY INVISIBLE (-6475 4175);
FORCEPROP 0 LAST CDS_SEC 1
J 0
(-6475 4175);
DISPLAY 1.021277 (-6475 4175);
DISPLAY INVISIBLE (-6475 4175);
FORCEPROP 1 LASTPIN (-6675 4150) $PN 1
J 2
(-6687 4162);
DISPLAY 0.489362 (-6687 4162);
PAINT MONO (-6687 4162);
FORCEPROP 1 LASTPIN (-6875 4150) $PN 2
J 2
(-6837 4162);
DISPLAY 0.489362 (-6837 4162);
PAINT MONO (-6837 4162);
FORCEPROP 1 LAST VALUE 0
J 0
(-6675 4150);
DISPLAY 0.489362 (-6675 4150);
PAINT SKYBLUE (-6675 4150);
FORCEPROP 2 LAST CDS_LIB pure_quanta
J 0
(-6775 4150);
DISPLAY INVISIBLE (-6775 4150);
FORCEPROP 1 LAST PATH I291
J 2
(-6725 4300);
DISPLAY 0.978723 (-6725 4300);
PAINT WHITE (-6725 4300);
DISPLAY INVISIBLE (-6725 4300);
FORCEPROP 1 LAST WATTAGE 1/16W
J 0
(-7175 4075);
DISPLAY 0.489362 (-7175 4075);
PAINT SKYBLUE (-7175 4075);
DISPLAY INVISIBLE (-7175 4075);
FORCEPROP 1 LAST MATERIAL CHIP
J 2
(-7200 4075);
DISPLAY 0.489362 (-7200 4075);
PAINT SKYBLUE (-7200 4075);
DISPLAY INVISIBLE (-7200 4075);
FORCEPROP 1 LAST TOLERANCE 5%
J 2
(-6750 4075);
DISPLAY 0.489362 (-6750 4075);
PAINT SKYBLUE (-6750 4075);
DISPLAY INVISIBLE (-6750 4075);
FORCEPROP 1 LAST PART_NUMBER CS00002JB38
J 2
(-6800 4200);
DISPLAY 0.489362 (-6800 4200);
PAINT SKYBLUE (-6800 4200);
DISPLAY INVISIBLE (-6800 4200);
FORCEPROP 1 LAST PACK_TYPE 0402LF
J 2
(-6825 4075);
DISPLAY 0.489362 (-6825 4075);
PAINT SKYBLUE (-6825 4075);
DISPLAY INVISIBLE (-6825 4075);
FORCEADD Q_RES..1
R 2
(-6775 4200);
FORCEPROP 1 LAST LOCATION R27
J 0
(-6525 4200);
DISPLAY 0.489362 (-6525 4200);
PAINT SKYBLUE (-6525 4200);
FORCEPROP 0 LAST $SEC 1
J 0
(-6475 4225);
DISPLAY 0.680851 (-6475 4225);
PAINT MONO (-6475 4225);
DISPLAY INVISIBLE (-6475 4225);
FORCEPROP 0 LAST CDS_SEC 1
J 0
(-6475 4225);
DISPLAY 1.021277 (-6475 4225);
DISPLAY INVISIBLE (-6475 4225);
FORCEPROP 1 LASTPIN (-6675 4200) $PN 1
J 2
(-6687 4212);
DISPLAY 0.489362 (-6687 4212);
PAINT MONO (-6687 4212);
FORCEPROP 1 LASTPIN (-6875 4200) $PN 2
J 2
(-6837 4212);
DISPLAY 0.489362 (-6837 4212);
PAINT MONO (-6837 4212);
FORCEPROP 1 LAST VALUE 0
J 0
(-6675 4200);
DISPLAY 0.489362 (-6675 4200);
PAINT SKYBLUE (-6675 4200);
FORCEPROP 2 LAST CDS_LIB pure_quanta
J 0
(-6775 4200);
DISPLAY INVISIBLE (-6775 4200);
FORCEPROP 1 LAST PATH I292
J 2
(-6725 4350);
DISPLAY 0.978723 (-6725 4350);
PAINT WHITE (-6725 4350);
DISPLAY INVISIBLE (-6725 4350);
FORCEPROP 1 LAST WATTAGE 1/16W
J 0
(-7175 4125);
DISPLAY 0.489362 (-7175 4125);
PAINT SKYBLUE (-7175 4125);
DISPLAY INVISIBLE (-7175 4125);
FORCEPROP 1 LAST MATERIAL CHIP
J 2
(-7200 4125);
DISPLAY 0.489362 (-7200 4125);
PAINT SKYBLUE (-7200 4125);
DISPLAY INVISIBLE (-7200 4125);
FORCEPROP 1 LAST TOLERANCE 5%
J 2
(-6750 4125);
DISPLAY 0.489362 (-6750 4125);
PAINT SKYBLUE (-6750 4125);
DISPLAY INVISIBLE (-6750 4125);
FORCEPROP 1 LAST PART_NUMBER CS00002JB38
J 2
(-6800 4250);
DISPLAY 0.489362 (-6800 4250);
PAINT SKYBLUE (-6800 4250);
DISPLAY INVISIBLE (-6800 4250);
FORCEPROP 1 LAST PACK_TYPE 0402LF
J 2
(-6825 4125);
DISPLAY 0.489362 (-6825 4125);
PAINT SKYBLUE (-6825 4125);
DISPLAY INVISIBLE (-6825 4125);
FORCEADD Q_RES..1
R 2
(-6775 3850);
FORCEPROP 1 LAST LOCATION R213
J 0
(-6525 3850);
DISPLAY 0.489362 (-6525 3850);
PAINT SKYBLUE (-6525 3850);
FORCEPROP 0 LAST $SEC 1
J 0
(-6525 3900);
DISPLAY 0.680851 (-6525 3900);
PAINT MONO (-6525 3900);
DISPLAY INVISIBLE (-6525 3900);
FORCEPROP 0 LAST CDS_SEC 1
J 0
(-6525 3900);
DISPLAY 1.021277 (-6525 3900);
DISPLAY INVISIBLE (-6525 3900);
FORCEPROP 1 LASTPIN (-6675 3850) $PN 1
J 2
(-6687 3862);
DISPLAY 0.489362 (-6687 3862);
PAINT MONO (-6687 3862);
FORCEPROP 1 LASTPIN (-6875 3850) $PN 2
J 2
(-6837 3862);
DISPLAY 0.489362 (-6837 3862);
PAINT MONO (-6837 3862);
FORCEPROP 1 LAST VALUE 0
J 0
(-6675 3850);
DISPLAY 0.489362 (-6675 3850);
PAINT SKYBLUE (-6675 3850);
FORCEPROP 2 LAST CDS_LIB pure_quanta
J 0
(-6775 3850);
DISPLAY INVISIBLE (-6775 3850);
FORCEPROP 1 LAST PATH I299
J 2
(-6725 4000);
DISPLAY 0.978723 (-6725 4000);
PAINT WHITE (-6725 4000);
DISPLAY INVISIBLE (-6725 4000);
FORCEPROP 1 LAST WATTAGE 1/16W
J 0
(-7175 3775);
DISPLAY 0.489362 (-7175 3775);
PAINT SKYBLUE (-7175 3775);
DISPLAY INVISIBLE (-7175 3775);
FORCEPROP 1 LAST MATERIAL CHIP
J 2
(-7200 3775);
DISPLAY 0.489362 (-7200 3775);
PAINT SKYBLUE (-7200 3775);
DISPLAY INVISIBLE (-7200 3775);
FORCEPROP 1 LAST TOLERANCE 5%
J 2
(-6750 3775);
DISPLAY 0.489362 (-6750 3775);
PAINT SKYBLUE (-6750 3775);
DISPLAY INVISIBLE (-6750 3775);
FORCEPROP 1 LAST PART_NUMBER CS00002JB38
J 2
(-6800 3900);
DISPLAY 0.489362 (-6800 3900);
PAINT SKYBLUE (-6800 3900);
DISPLAY INVISIBLE (-6800 3900);
FORCEPROP 1 LAST PACK_TYPE 0402LF
J 2
(-6825 3775);
DISPLAY 0.489362 (-6825 3775);
PAINT SKYBLUE (-6825 3775);
DISPLAY INVISIBLE (-6825 3775);
FORCEADD Q_CRYSTAL..1
(-3275 1825);
FORCEPROP 1 LAST LOCATION Y3
J 0
(-3350 2025);
DISPLAY 0.489362 (-3350 2025);
PAINT SKYBLUE (-3350 2025);
FORCEPROP 0 LAST $SEC 1
J 0
(-3350 2175);
DISPLAY 0.680851 (-3350 2175);
PAINT MONO (-3350 2175);
DISPLAY INVISIBLE (-3350 2175);
FORCEPROP 0 LAST CDS_SEC 1
J 0
(-3350 2175);
DISPLAY 1.021277 (-3350 2175);
DISPLAY INVISIBLE (-3350 2175);
FORCEPROP 0 LASTPIN (-3375 1825) $PN 1
J 2
(-3385 1835);
DISPLAY 0.489362 (-3385 1835);
PAINT MONO (-3385 1835);
FORCEPROP 0 LASTPIN (-3175 1825) $PN 2
J 0
(-3165 1835);
DISPLAY 0.489362 (-3165 1835);
PAINT MONO (-3165 1835);
FORCEPROP 2 LAST VALUE 32.768KHZ
J 0
(-3350 2120);
DISPLAY 0.489362 (-3350 2120);
PAINT SKYBLUE (-3350 2120);
FORCEPROP 1 LAST MATERIAL IC
J 0
(-3350 1925);
DISPLAY 0.489362 (-3350 1925);
PAINT SKYBLUE (-3350 1925);
FORCEPROP 1 LAST PART_NUMBER BG632768012
J 0
(-3350 1980);
DISPLAY 0.489362 (-3350 1980);
PAINT SKYBLUE (-3350 1980);
FORCEPROP 2 LAST PACK_TYPE SMLF
J 0
(-3350 2070);
DISPLAY 0.489362 (-3350 2070);
PAINT SKYBLUE (-3350 2070);
FORCEPROP 2 LAST CDS_LIB pure_quanta
J 0
(-3275 1825);
DISPLAY INVISIBLE (-3275 1825);
FORCEPROP 1 LAST NEEDS_NO_SIZE TRUE
J 0
(-3275 1825);
DISPLAY 0.468085 (-3275 1825);
PAINT GREEN (-3275 1825);
DISPLAY INVISIBLE (-3275 1825);
FORCEPROP 1 LAST PATH I3
J 0
(-3225 1910);
DISPLAY 0.723404 (-3225 1910);
PAINT GREEN (-3225 1910);
DISPLAY INVISIBLE (-3225 1910);
FORCEADD Q_RES..1
R 2
(-6775 3900);
FORCEPROP 1 LAST LOCATION R212
J 0
(-6525 3900);
DISPLAY 0.489362 (-6525 3900);
PAINT SKYBLUE (-6525 3900);
FORCEPROP 0 LAST $SEC 1
J 0
(-6525 3950);
DISPLAY 0.680851 (-6525 3950);
PAINT MONO (-6525 3950);
DISPLAY INVISIBLE (-6525 3950);
FORCEPROP 0 LAST CDS_SEC 1
J 0
(-6525 3950);
DISPLAY 1.021277 (-6525 3950);
DISPLAY INVISIBLE (-6525 3950);
FORCEPROP 1 LASTPIN (-6675 3900) $PN 1
J 2
(-6687 3912);
DISPLAY 0.489362 (-6687 3912);
PAINT MONO (-6687 3912);
FORCEPROP 1 LASTPIN (-6875 3900) $PN 2
J 2
(-6837 3912);
DISPLAY 0.489362 (-6837 3912);
PAINT MONO (-6837 3912);
FORCEPROP 1 LAST VALUE 0
J 0
(-6675 3900);
DISPLAY 0.489362 (-6675 3900);
PAINT SKYBLUE (-6675 3900);
FORCEPROP 2 LAST CDS_LIB pure_quanta
J 0
(-6775 3900);
DISPLAY INVISIBLE (-6775 3900);
FORCEPROP 1 LAST PATH I300
J 2
(-6725 4050);
DISPLAY 0.978723 (-6725 4050);
PAINT WHITE (-6725 4050);
DISPLAY INVISIBLE (-6725 4050);
FORCEPROP 1 LAST WATTAGE 1/16W
J 0
(-7175 3825);
DISPLAY 0.489362 (-7175 3825);
PAINT SKYBLUE (-7175 3825);
DISPLAY INVISIBLE (-7175 3825);
FORCEPROP 1 LAST MATERIAL CHIP
J 2
(-7200 3825);
DISPLAY 0.489362 (-7200 3825);
PAINT SKYBLUE (-7200 3825);
DISPLAY INVISIBLE (-7200 3825);
FORCEPROP 1 LAST TOLERANCE 5%
J 2
(-6750 3825);
DISPLAY 0.489362 (-6750 3825);
PAINT SKYBLUE (-6750 3825);
DISPLAY INVISIBLE (-6750 3825);
FORCEPROP 1 LAST PART_NUMBER CS00002JB38
J 2
(-6800 3950);
DISPLAY 0.489362 (-6800 3950);
PAINT SKYBLUE (-6800 3950);
DISPLAY INVISIBLE (-6800 3950);
FORCEPROP 1 LAST PACK_TYPE 0402LF
J 2
(-6825 3825);
DISPLAY 0.489362 (-6825 3825);
PAINT SKYBLUE (-6825 3825);
DISPLAY INVISIBLE (-6825 3825);
FORCEADD OFFPAGE..3
R 2
(-7825 3850);
FORCEPROP 2 LAST $XR0 118 
J 0
(-8135 3850);
DISPLAY 0.638298 (-8135 3850);
PAINT MONO (-8135 3850);
FORCEPROP 2 LAST CDS_LIB standard
J 0
(-7825 3850);
DISPLAY INVISIBLE (-7825 3850);
FORCEPROP 1 LAST OFFPAGE TRUE
J 2
(-8150 3725);
DISPLAY 0.872340 (-8150 3725);
PAINT GREEN (-8150 3725);
DISPLAY INVISIBLE (-8150 3725);
FORCEPROP 1 LAST COMMENT_BODY TRUE
J 2
(-7775 3750);
DISPLAY 0.872340 (-7775 3750);
PAINT PEACH (-7775 3750);
DISPLAY INVISIBLE (-7775 3750);
FORCEPROP 2 LAST PATH I302
J 0
(-7775 3925);
DISPLAY 1.021277 (-7775 3925);
DISPLAY INVISIBLE (-7775 3925);
FORCEADD OFFPAGE..2
R 2
(-7825 3900);
FORCEPROP 2 LAST $XR0 118 
J 0
(-8110 3900);
DISPLAY 0.638298 (-8110 3900);
PAINT MONO (-8110 3900);
FORCEPROP 2 LAST CDS_LIB standard
J 0
(-7825 3900);
DISPLAY INVISIBLE (-7825 3900);
FORCEPROP 1 LAST OFFPAGE TRUE
J 2
(-8150 3775);
DISPLAY 0.872340 (-8150 3775);
PAINT GREEN (-8150 3775);
DISPLAY INVISIBLE (-8150 3775);
FORCEPROP 1 LAST COMMENT_BODY TRUE
J 2
(-7780 3805);
DISPLAY 0.872340 (-7780 3805);
PAINT GREEN (-7780 3805);
DISPLAY INVISIBLE (-7780 3805);
FORCEPROP 2 LAST PATH I303
J 0
(-7775 3975);
DISPLAY 1.021277 (-7775 3975);
DISPLAY INVISIBLE (-7775 3975);
FORCEADD UNIVERSAL_POWER..1
(-7350 2150);
FORCEPROP 3 LASTPIN (-7350 2100) SIG_NAME PVDD18_S5_P0\g
J 0
(-7340 2110);
DISPLAY 0.659574 (-7340 2110);
PAINT MONO (-7340 2110);
DISPLAY INVISIBLE (-7340 2110);
FORCEPROP 1 LAST HDL_POWER PVDD18_S5_P0
J 1
(-7350 2200);
DISPLAY 0.489362 (-7350 2200);
PAINT GREEN (-7350 2200);
FORCEPROP 2 LAST CDS_LIB pure_quanta_power
J 0
(-7350 2150);
DISPLAY INVISIBLE (-7350 2150);
FORCEPROP 1 LAST PATH I304
J 0
(-7300 2175);
DISPLAY 0.872340 (-7300 2175);
PAINT AQUA (-7300 2175);
DISPLAY INVISIBLE (-7300 2175);
FORCEADD Q_RES..1
(-7700 2000);
FORCEPROP 1 LAST LOCATION R438
J 0
(-7900 2000);
DISPLAY 0.489362 (-7900 2000);
PAINT SKYBLUE (-7900 2000);
FORCEPROP 0 LAST $SEC 1
J 0
(-7850 2050);
DISPLAY 0.680851 (-7850 2050);
PAINT MONO (-7850 2050);
DISPLAY INVISIBLE (-7850 2050);
FORCEPROP 0 LAST CDS_SEC 1
J 0
(-7850 2050);
DISPLAY 1.021277 (-7850 2050);
DISPLAY INVISIBLE (-7850 2050);
FORCEPROP 1 LASTPIN (-7800 2000) $PN 1
J 0
(-7788 2012);
DISPLAY 0.489362 (-7788 2012);
PAINT MONO (-7788 2012);
FORCEPROP 1 LASTPIN (-7600 2000) $PN 2
J 0
(-7638 2012);
DISPLAY 0.489362 (-7638 2012);
PAINT MONO (-7638 2012);
FORCEPROP 1 LAST VALUE 4.7K
J 0
(-7600 2000);
DISPLAY 0.489362 (-7600 2000);
PAINT SKYBLUE (-7600 2000);
FORCEPROP 2 LAST CDS_LIB pure_quanta
J 0
(-7700 2000);
DISPLAY INVISIBLE (-7700 2000);
FORCEPROP 1 LAST PATH I305
J 0
(-7750 2150);
DISPLAY 0.978723 (-7750 2150);
PAINT WHITE (-7750 2150);
DISPLAY INVISIBLE (-7750 2150);
FORCEPROP 1 LAST WATTAGE 1/16W
J 2
(-7725 1850);
DISPLAY 0.510638 (-7725 1850);
PAINT SKYBLUE (-7725 1850);
DISPLAY INVISIBLE (-7725 1850);
FORCEPROP 1 LAST MATERIAL CHIP
J 0
(-7600 1975);
DISPLAY 0.489362 (-7600 1975);
PAINT SKYBLUE (-7600 1975);
DISPLAY INVISIBLE (-7600 1975);
FORCEPROP 1 LAST TOLERANCE 5%
J 0
(-7575 2000);
DISPLAY 0.510638 (-7575 2000);
PAINT SKYBLUE (-7575 2000);
DISPLAY INVISIBLE (-7575 2000);
FORCEPROP 1 LAST PART_NUMBER TMP_QCS24702JB38
J 0
(-7750 2100);
DISPLAY 0.510638 (-7750 2100);
PAINT SKYBLUE (-7750 2100);
DISPLAY INVISIBLE (-7750 2100);
FORCEPROP 1 LAST PACK_TYPE 0402LF
J 0
(-7450 1850);
DISPLAY 0.510638 (-7450 1850);
PAINT SKYBLUE (-7450 1850);
DISPLAY INVISIBLE (-7450 1850);
FORCEADD Q_RES..1
(-7700 1650);
FORCEPROP 1 LAST LOCATION R445
J 0
(-7900 1650);
DISPLAY 0.489362 (-7900 1650);
PAINT SKYBLUE (-7900 1650);
FORCEPROP 0 LAST $SEC 1
J 0
(-7850 1700);
DISPLAY 0.680851 (-7850 1700);
PAINT MONO (-7850 1700);
DISPLAY INVISIBLE (-7850 1700);
FORCEPROP 0 LAST CDS_SEC 1
J 0
(-7850 1700);
DISPLAY 1.021277 (-7850 1700);
DISPLAY INVISIBLE (-7850 1700);
FORCEPROP 1 LASTPIN (-7800 1650) $PN 1
J 0
(-7788 1662);
DISPLAY 0.489362 (-7788 1662);
PAINT MONO (-7788 1662);
FORCEPROP 1 LASTPIN (-7600 1650) $PN 2
J 0
(-7638 1662);
DISPLAY 0.489362 (-7638 1662);
PAINT MONO (-7638 1662);
FORCEPROP 1 LAST VALUE 4.7K
J 0
(-7600 1650);
DISPLAY 0.489362 (-7600 1650);
PAINT SKYBLUE (-7600 1650);
FORCEPROP 2 LAST CDS_LIB pure_quanta
J 0
(-7700 1650);
DISPLAY INVISIBLE (-7700 1650);
FORCEPROP 1 LAST PATH I310
J 0
(-7750 1800);
DISPLAY 0.978723 (-7750 1800);
PAINT WHITE (-7750 1800);
DISPLAY INVISIBLE (-7750 1800);
FORCEPROP 1 LAST WATTAGE 1/16W
J 2
(-7725 1500);
DISPLAY 0.510638 (-7725 1500);
PAINT SKYBLUE (-7725 1500);
DISPLAY INVISIBLE (-7725 1500);
FORCEPROP 1 LAST MATERIAL CHIP
J 0
(-7600 1625);
DISPLAY 0.489362 (-7600 1625);
PAINT SKYBLUE (-7600 1625);
DISPLAY INVISIBLE (-7600 1625);
FORCEPROP 1 LAST TOLERANCE 5%
J 0
(-7575 1650);
DISPLAY 0.510638 (-7575 1650);
PAINT SKYBLUE (-7575 1650);
DISPLAY INVISIBLE (-7575 1650);
FORCEPROP 1 LAST PART_NUMBER TMP_QCS24702JB38
J 0
(-7750 1750);
DISPLAY 0.510638 (-7750 1750);
PAINT SKYBLUE (-7750 1750);
DISPLAY INVISIBLE (-7750 1750);
FORCEPROP 1 LAST PACK_TYPE 0402LF
J 0
(-7450 1500);
DISPLAY 0.510638 (-7450 1500);
PAINT SKYBLUE (-7450 1500);
DISPLAY INVISIBLE (-7450 1500);
FORCEADD Q_RES..1
(-7700 1700);
FORCEPROP 1 LAST LOCATION R444
J 0
(-7900 1700);
DISPLAY 0.489362 (-7900 1700);
PAINT SKYBLUE (-7900 1700);
FORCEPROP 0 LAST $SEC 1
J 0
(-7850 1750);
DISPLAY 0.680851 (-7850 1750);
PAINT MONO (-7850 1750);
DISPLAY INVISIBLE (-7850 1750);
FORCEPROP 0 LAST CDS_SEC 1
J 0
(-7850 1750);
DISPLAY 1.021277 (-7850 1750);
DISPLAY INVISIBLE (-7850 1750);
FORCEPROP 1 LASTPIN (-7800 1700) $PN 1
J 0
(-7788 1712);
DISPLAY 0.489362 (-7788 1712);
PAINT MONO (-7788 1712);
FORCEPROP 1 LASTPIN (-7600 1700) $PN 2
J 0
(-7638 1712);
DISPLAY 0.489362 (-7638 1712);
PAINT MONO (-7638 1712);
FORCEPROP 1 LAST VALUE 4.7K
J 0
(-7600 1700);
DISPLAY 0.489362 (-7600 1700);
PAINT SKYBLUE (-7600 1700);
FORCEPROP 2 LAST CDS_LIB pure_quanta
J 0
(-7700 1700);
DISPLAY INVISIBLE (-7700 1700);
FORCEPROP 1 LAST PATH I311
J 0
(-7750 1850);
DISPLAY 0.978723 (-7750 1850);
PAINT WHITE (-7750 1850);
DISPLAY INVISIBLE (-7750 1850);
FORCEPROP 1 LAST WATTAGE 1/16W
J 2
(-7725 1550);
DISPLAY 0.510638 (-7725 1550);
PAINT SKYBLUE (-7725 1550);
DISPLAY INVISIBLE (-7725 1550);
FORCEPROP 1 LAST MATERIAL CHIP
J 0
(-7600 1675);
DISPLAY 0.489362 (-7600 1675);
PAINT SKYBLUE (-7600 1675);
DISPLAY INVISIBLE (-7600 1675);
FORCEPROP 1 LAST TOLERANCE 5%
J 0
(-7575 1700);
DISPLAY 0.510638 (-7575 1700);
PAINT SKYBLUE (-7575 1700);
DISPLAY INVISIBLE (-7575 1700);
FORCEPROP 1 LAST PART_NUMBER TMP_QCS24702JB38
J 0
(-7750 1800);
DISPLAY 0.510638 (-7750 1800);
PAINT SKYBLUE (-7750 1800);
DISPLAY INVISIBLE (-7750 1800);
FORCEPROP 1 LAST PACK_TYPE 0402LF
J 0
(-7450 1550);
DISPLAY 0.510638 (-7450 1550);
PAINT SKYBLUE (-7450 1550);
DISPLAY INVISIBLE (-7450 1550);
FORCEADD Q_RES..1
(-7700 1600);
FORCEPROP 1 LAST LOCATION R446
J 0
(-7900 1600);
DISPLAY 0.489362 (-7900 1600);
PAINT SKYBLUE (-7900 1600);
FORCEPROP 0 LAST $SEC 1
J 0
(-7875 1650);
DISPLAY 0.680851 (-7875 1650);
PAINT MONO (-7875 1650);
DISPLAY INVISIBLE (-7875 1650);
FORCEPROP 0 LAST CDS_SEC 1
J 0
(-7875 1650);
DISPLAY 1.021277 (-7875 1650);
DISPLAY INVISIBLE (-7875 1650);
FORCEPROP 1 LASTPIN (-7800 1600) $PN 1
J 0
(-7788 1612);
DISPLAY 0.489362 (-7788 1612);
PAINT MONO (-7788 1612);
FORCEPROP 1 LASTPIN (-7600 1600) $PN 2
J 0
(-7638 1612);
DISPLAY 0.489362 (-7638 1612);
PAINT MONO (-7638 1612);
FORCEPROP 1 LAST VALUE 4.7K
J 0
(-7600 1600);
DISPLAY 0.489362 (-7600 1600);
PAINT SKYBLUE (-7600 1600);
FORCEPROP 2 LAST CDS_LIB pure_quanta
J 0
(-7700 1600);
DISPLAY INVISIBLE (-7700 1600);
FORCEPROP 1 LAST PATH I312
J 0
(-7750 1750);
DISPLAY 0.978723 (-7750 1750);
PAINT WHITE (-7750 1750);
DISPLAY INVISIBLE (-7750 1750);
FORCEPROP 1 LAST WATTAGE 1/16W
J 2
(-7725 1450);
DISPLAY 0.510638 (-7725 1450);
PAINT SKYBLUE (-7725 1450);
DISPLAY INVISIBLE (-7725 1450);
FORCEPROP 1 LAST MATERIAL CHIP
J 0
(-7600 1575);
DISPLAY 0.489362 (-7600 1575);
PAINT SKYBLUE (-7600 1575);
DISPLAY INVISIBLE (-7600 1575);
FORCEPROP 1 LAST TOLERANCE 5%
J 0
(-7575 1600);
DISPLAY 0.510638 (-7575 1600);
PAINT SKYBLUE (-7575 1600);
DISPLAY INVISIBLE (-7575 1600);
FORCEPROP 1 LAST PART_NUMBER TMP_QCS24702JB38
J 0
(-7750 1700);
DISPLAY 0.510638 (-7750 1700);
PAINT SKYBLUE (-7750 1700);
DISPLAY INVISIBLE (-7750 1700);
FORCEPROP 1 LAST PACK_TYPE 0402LF
J 0
(-7450 1450);
DISPLAY 0.510638 (-7450 1450);
PAINT SKYBLUE (-7450 1450);
DISPLAY INVISIBLE (-7450 1450);
FORCEADD Q_RES..1
(-7700 1500);
FORCEPROP 1 LAST LOCATION R448
J 0
(-7900 1500);
DISPLAY 0.489362 (-7900 1500);
PAINT SKYBLUE (-7900 1500);
FORCEPROP 0 LAST $SEC 1
J 0
(-7875 1550);
DISPLAY 0.680851 (-7875 1550);
PAINT MONO (-7875 1550);
DISPLAY INVISIBLE (-7875 1550);
FORCEPROP 0 LAST CDS_SEC 1
J 0
(-7875 1550);
DISPLAY 1.021277 (-7875 1550);
DISPLAY INVISIBLE (-7875 1550);
FORCEPROP 1 LASTPIN (-7800 1500) $PN 1
J 0
(-7788 1512);
DISPLAY 0.489362 (-7788 1512);
PAINT MONO (-7788 1512);
FORCEPROP 1 LASTPIN (-7600 1500) $PN 2
J 0
(-7638 1512);
DISPLAY 0.489362 (-7638 1512);
PAINT MONO (-7638 1512);
FORCEPROP 1 LAST MATERIAL EMPTY
J 0
(-8025 1500);
DISPLAY 0.489362 (-8025 1500);
PAINT RED (-8025 1500);
FORCEPROP 1 LAST VALUE 4.7K
J 0
(-7600 1500);
DISPLAY 0.489362 (-7600 1500);
PAINT SKYBLUE (-7600 1500);
FORCEPROP 2 LAST CDS_LIB pure_quanta
J 0
(-7700 1500);
DISPLAY INVISIBLE (-7700 1500);
FORCEPROP 1 LAST PATH I313
J 0
(-7750 1650);
DISPLAY 0.978723 (-7750 1650);
PAINT WHITE (-7750 1650);
DISPLAY INVISIBLE (-7750 1650);
FORCEPROP 1 LAST WATTAGE 1/16W
J 2
(-7725 1350);
DISPLAY 0.510638 (-7725 1350);
PAINT SKYBLUE (-7725 1350);
DISPLAY INVISIBLE (-7725 1350);
FORCEPROP 1 LAST TOLERANCE 5%
J 0
(-7575 1500);
DISPLAY 0.510638 (-7575 1500);
PAINT SKYBLUE (-7575 1500);
DISPLAY INVISIBLE (-7575 1500);
FORCEPROP 1 LAST PART_NUMBER TMP_QCS24702JB38
J 0
(-7750 1600);
DISPLAY 0.510638 (-7750 1600);
PAINT SKYBLUE (-7750 1600);
DISPLAY INVISIBLE (-7750 1600);
FORCEPROP 1 LAST PACK_TYPE 0402LF
J 0
(-7450 1350);
DISPLAY 0.510638 (-7450 1350);
PAINT SKYBLUE (-7450 1350);
DISPLAY INVISIBLE (-7450 1350);
FORCEADD Q_RES..1
(-7700 1550);
FORCEPROP 1 LAST LOCATION R447
J 0
(-7900 1550);
DISPLAY 0.489362 (-7900 1550);
PAINT SKYBLUE (-7900 1550);
FORCEPROP 0 LAST $SEC 1
J 0
(-7875 1600);
DISPLAY 0.680851 (-7875 1600);
PAINT MONO (-7875 1600);
DISPLAY INVISIBLE (-7875 1600);
FORCEPROP 0 LAST CDS_SEC 1
J 0
(-7875 1600);
DISPLAY 1.021277 (-7875 1600);
DISPLAY INVISIBLE (-7875 1600);
FORCEPROP 1 LASTPIN (-7800 1550) $PN 1
J 0
(-7788 1562);
DISPLAY 0.489362 (-7788 1562);
PAINT MONO (-7788 1562);
FORCEPROP 1 LASTPIN (-7600 1550) $PN 2
J 0
(-7638 1562);
DISPLAY 0.489362 (-7638 1562);
PAINT MONO (-7638 1562);
FORCEPROP 1 LAST VALUE 4.7K
J 0
(-7600 1550);
DISPLAY 0.489362 (-7600 1550);
PAINT SKYBLUE (-7600 1550);
FORCEPROP 2 LAST CDS_LIB pure_quanta
J 0
(-7700 1550);
DISPLAY INVISIBLE (-7700 1550);
FORCEPROP 1 LAST PATH I314
J 0
(-7750 1700);
DISPLAY 0.978723 (-7750 1700);
PAINT WHITE (-7750 1700);
DISPLAY INVISIBLE (-7750 1700);
FORCEPROP 1 LAST WATTAGE 1/16W
J 2
(-7725 1400);
DISPLAY 0.510638 (-7725 1400);
PAINT SKYBLUE (-7725 1400);
DISPLAY INVISIBLE (-7725 1400);
FORCEPROP 1 LAST MATERIAL CHIP
J 0
(-7600 1525);
DISPLAY 0.489362 (-7600 1525);
PAINT SKYBLUE (-7600 1525);
DISPLAY INVISIBLE (-7600 1525);
FORCEPROP 1 LAST TOLERANCE 5%
J 0
(-7575 1550);
DISPLAY 0.510638 (-7575 1550);
PAINT SKYBLUE (-7575 1550);
DISPLAY INVISIBLE (-7575 1550);
FORCEPROP 1 LAST PART_NUMBER TMP_QCS24702JB38
J 0
(-7750 1650);
DISPLAY 0.510638 (-7750 1650);
PAINT SKYBLUE (-7750 1650);
DISPLAY INVISIBLE (-7750 1650);
FORCEPROP 1 LAST PACK_TYPE 0402LF
J 0
(-7450 1400);
DISPLAY 0.510638 (-7450 1400);
PAINT SKYBLUE (-7450 1400);
DISPLAY INVISIBLE (-7450 1400);
FORCEADD Q_RES..1
(-7700 1450);
FORCEPROP 1 LAST LOCATION R449
J 0
(-7900 1450);
DISPLAY 0.489362 (-7900 1450);
PAINT SKYBLUE (-7900 1450);
FORCEPROP 0 LAST $SEC 1
J 0
(-7875 1500);
DISPLAY 0.680851 (-7875 1500);
PAINT MONO (-7875 1500);
DISPLAY INVISIBLE (-7875 1500);
FORCEPROP 0 LAST CDS_SEC 1
J 0
(-7875 1500);
DISPLAY 1.021277 (-7875 1500);
DISPLAY INVISIBLE (-7875 1500);
FORCEPROP 1 LASTPIN (-7800 1450) $PN 1
J 0
(-7788 1462);
DISPLAY 0.489362 (-7788 1462);
PAINT MONO (-7788 1462);
FORCEPROP 1 LASTPIN (-7600 1450) $PN 2
J 0
(-7638 1462);
DISPLAY 0.489362 (-7638 1462);
PAINT MONO (-7638 1462);
FORCEPROP 1 LAST MATERIAL EMPTY
J 0
(-8025 1450);
DISPLAY 0.489362 (-8025 1450);
PAINT RED (-8025 1450);
FORCEPROP 1 LAST VALUE 4.7K
J 0
(-7600 1450);
DISPLAY 0.489362 (-7600 1450);
PAINT SKYBLUE (-7600 1450);
FORCEPROP 2 LAST CDS_LIB pure_quanta
J 0
(-7700 1450);
DISPLAY INVISIBLE (-7700 1450);
FORCEPROP 1 LAST PATH I315
J 0
(-7750 1600);
DISPLAY 0.978723 (-7750 1600);
PAINT WHITE (-7750 1600);
DISPLAY INVISIBLE (-7750 1600);
FORCEPROP 1 LAST WATTAGE 1/16W
J 2
(-7725 1300);
DISPLAY 0.510638 (-7725 1300);
PAINT SKYBLUE (-7725 1300);
DISPLAY INVISIBLE (-7725 1300);
FORCEPROP 1 LAST TOLERANCE 5%
J 0
(-7575 1450);
DISPLAY 0.510638 (-7575 1450);
PAINT SKYBLUE (-7575 1450);
DISPLAY INVISIBLE (-7575 1450);
FORCEPROP 1 LAST PART_NUMBER TMP_QCS24702JB38
J 0
(-7750 1550);
DISPLAY 0.510638 (-7750 1550);
PAINT SKYBLUE (-7750 1550);
DISPLAY INVISIBLE (-7750 1550);
FORCEPROP 1 LAST PACK_TYPE 0402LF
J 0
(-7450 1300);
DISPLAY 0.510638 (-7450 1300);
PAINT SKYBLUE (-7450 1300);
DISPLAY INVISIBLE (-7450 1300);
FORCEADD Q_RES..1
(-7700 1400);
FORCEPROP 1 LAST LOCATION R450
J 0
(-7900 1400);
DISPLAY 0.489362 (-7900 1400);
PAINT SKYBLUE (-7900 1400);
FORCEPROP 0 LAST $SEC 1
J 0
(-7875 1450);
DISPLAY 0.680851 (-7875 1450);
PAINT MONO (-7875 1450);
DISPLAY INVISIBLE (-7875 1450);
FORCEPROP 0 LAST CDS_SEC 1
J 0
(-7875 1450);
DISPLAY 1.021277 (-7875 1450);
DISPLAY INVISIBLE (-7875 1450);
FORCEPROP 1 LASTPIN (-7800 1400) $PN 1
J 0
(-7788 1412);
DISPLAY 0.489362 (-7788 1412);
PAINT MONO (-7788 1412);
FORCEPROP 1 LASTPIN (-7600 1400) $PN 2
J 0
(-7638 1412);
DISPLAY 0.489362 (-7638 1412);
PAINT MONO (-7638 1412);
FORCEPROP 1 LAST VALUE 4.7K
J 0
(-7600 1400);
DISPLAY 0.489362 (-7600 1400);
PAINT SKYBLUE (-7600 1400);
FORCEPROP 2 LAST CDS_LIB pure_quanta
J 0
(-7700 1400);
DISPLAY INVISIBLE (-7700 1400);
FORCEPROP 1 LAST PATH I316
J 0
(-7750 1550);
DISPLAY 0.978723 (-7750 1550);
PAINT WHITE (-7750 1550);
DISPLAY INVISIBLE (-7750 1550);
FORCEPROP 1 LAST WATTAGE 1/16W
J 2
(-7725 1250);
DISPLAY 0.510638 (-7725 1250);
PAINT SKYBLUE (-7725 1250);
DISPLAY INVISIBLE (-7725 1250);
FORCEPROP 1 LAST MATERIAL CHIP
J 0
(-7600 1375);
DISPLAY 0.489362 (-7600 1375);
PAINT SKYBLUE (-7600 1375);
DISPLAY INVISIBLE (-7600 1375);
FORCEPROP 1 LAST TOLERANCE 5%
J 0
(-7575 1400);
DISPLAY 0.510638 (-7575 1400);
PAINT SKYBLUE (-7575 1400);
DISPLAY INVISIBLE (-7575 1400);
FORCEPROP 1 LAST PART_NUMBER TMP_QCS24702JB38
J 0
(-7750 1500);
DISPLAY 0.510638 (-7750 1500);
PAINT SKYBLUE (-7750 1500);
DISPLAY INVISIBLE (-7750 1500);
FORCEPROP 1 LAST PACK_TYPE 0402LF
J 0
(-7450 1250);
DISPLAY 0.510638 (-7450 1250);
PAINT SKYBLUE (-7450 1250);
DISPLAY INVISIBLE (-7450 1250);
FORCEADD OFFPAGE..2
R 2
(-8675 2000);
FORCEPROP 2 LAST $XR1 28 
J 0
(-8989 2000);
DISPLAY 0.638298 (-8989 2000);
PAINT MONO (-8989 2000);
FORCEPROP 2 LAST $XR0 80 
J 0
(-8899 2000);
DISPLAY 0.638298 (-8899 2000);
PAINT MONO (-8899 2000);
FORCEPROP 2 LAST CDS_LIB standard
J 2
(-8675 2000);
DISPLAY INVISIBLE (-8675 2000);
FORCEPROP 1 LAST OFFPAGE TRUE
J 2
(-9000 1875);
DISPLAY 0.872340 (-9000 1875);
PAINT GREEN (-9000 1875);
DISPLAY INVISIBLE (-9000 1875);
FORCEPROP 1 LAST COMMENT_BODY TRUE
J 2
(-8630 1905);
DISPLAY 0.872340 (-8630 1905);
PAINT GREEN (-8630 1905);
DISPLAY INVISIBLE (-8630 1905);
FORCEPROP 2 LAST PATH I317
J 0
(-8875 2050);
DISPLAY 1.021277 (-8875 2050);
DISPLAY INVISIBLE (-8875 2050);
FORCEADD OFFPAGE..2
R 2
(-8675 1850);
FORCEPROP 2 LAST $XR1 28 
J 0
(-8989 1850);
DISPLAY 0.638298 (-8989 1850);
PAINT MONO (-8989 1850);
FORCEPROP 2 LAST $XR0 80 
J 0
(-8899 1850);
DISPLAY 0.638298 (-8899 1850);
PAINT MONO (-8899 1850);
FORCEPROP 2 LAST CDS_LIB standard
J 0
(-8675 1850);
DISPLAY INVISIBLE (-8675 1850);
FORCEPROP 1 LAST OFFPAGE TRUE
J 2
(-9000 1725);
DISPLAY 0.872340 (-9000 1725);
PAINT GREEN (-9000 1725);
DISPLAY INVISIBLE (-9000 1725);
FORCEPROP 1 LAST COMMENT_BODY TRUE
J 2
(-8630 1755);
DISPLAY 0.872340 (-8630 1755);
PAINT GREEN (-8630 1755);
DISPLAY INVISIBLE (-8630 1755);
FORCEPROP 2 LAST PATH I319
J 0
(-8875 1900);
DISPLAY 1.021277 (-8875 1900);
DISPLAY INVISIBLE (-8875 1900);
FORCEADD OFFPAGE..2
R 2
(-8675 1800);
FORCEPROP 2 LAST $XR2 84 
J 0
(-9079 1800);
DISPLAY 0.638298 (-9079 1800);
PAINT MONO (-9079 1800);
FORCEPROP 2 LAST $XR1 80 
J 0
(-8989 1800);
DISPLAY 0.638298 (-8989 1800);
PAINT MONO (-8989 1800);
FORCEPROP 2 LAST $XR0 28 
J 0
(-8899 1800);
DISPLAY 0.638298 (-8899 1800);
PAINT MONO (-8899 1800);
FORCEPROP 2 LAST CDS_LIB standard
J 0
(-8675 1800);
DISPLAY INVISIBLE (-8675 1800);
FORCEPROP 1 LAST OFFPAGE TRUE
J 2
(-9000 1675);
DISPLAY 0.872340 (-9000 1675);
PAINT GREEN (-9000 1675);
DISPLAY INVISIBLE (-9000 1675);
FORCEPROP 1 LAST COMMENT_BODY TRUE
J 2
(-8630 1705);
DISPLAY 0.872340 (-8630 1705);
PAINT GREEN (-8630 1705);
DISPLAY INVISIBLE (-8630 1705);
FORCEPROP 2 LAST PATH I320
J 0
(-8875 1850);
DISPLAY 1.021277 (-8875 1850);
DISPLAY INVISIBLE (-8875 1850);
FORCEADD OFFPAGE..2
R 2
(-8675 1750);
FORCEPROP 2 LAST $XR3 84 
J 0
(-9169 1750);
DISPLAY 0.638298 (-9169 1750);
PAINT MONO (-9169 1750);
FORCEPROP 2 LAST $XR2 77 
J 0
(-9079 1750);
DISPLAY 0.638298 (-9079 1750);
PAINT MONO (-9079 1750);
FORCEPROP 2 LAST $XR1 80 
J 0
(-8989 1750);
DISPLAY 0.638298 (-8989 1750);
PAINT MONO (-8989 1750);
FORCEPROP 2 LAST $XR0 28 
J 0
(-8899 1750);
DISPLAY 0.638298 (-8899 1750);
PAINT MONO (-8899 1750);
FORCEPROP 2 LAST CDS_LIB standard
J 0
(-8675 1750);
DISPLAY INVISIBLE (-8675 1750);
FORCEPROP 1 LAST OFFPAGE TRUE
J 2
(-9000 1625);
DISPLAY 0.872340 (-9000 1625);
PAINT GREEN (-9000 1625);
DISPLAY INVISIBLE (-9000 1625);
FORCEPROP 1 LAST COMMENT_BODY TRUE
J 2
(-8630 1655);
DISPLAY 0.872340 (-8630 1655);
PAINT GREEN (-8630 1655);
DISPLAY INVISIBLE (-8630 1655);
FORCEPROP 2 LAST PATH I321
J 0
(-8875 1800);
DISPLAY 1.021277 (-8875 1800);
DISPLAY INVISIBLE (-8875 1800);
FORCEADD OFFPAGE..2
R 2
(-8675 1700);
FORCEPROP 2 LAST $XR1 28 
J 0
(-8989 1700);
DISPLAY 0.638298 (-8989 1700);
PAINT MONO (-8989 1700);
FORCEPROP 2 LAST $XR0 81 
J 0
(-8899 1700);
DISPLAY 0.638298 (-8899 1700);
PAINT MONO (-8899 1700);
FORCEPROP 2 LAST CDS_LIB standard
J 0
(-8675 1700);
DISPLAY INVISIBLE (-8675 1700);
FORCEPROP 1 LAST OFFPAGE TRUE
J 2
(-9000 1575);
DISPLAY 0.872340 (-9000 1575);
PAINT GREEN (-9000 1575);
DISPLAY INVISIBLE (-9000 1575);
FORCEPROP 1 LAST COMMENT_BODY TRUE
J 2
(-8630 1605);
DISPLAY 0.872340 (-8630 1605);
PAINT GREEN (-8630 1605);
DISPLAY INVISIBLE (-8630 1605);
FORCEPROP 2 LAST PATH I322
J 0
(-8875 1750);
DISPLAY 1.021277 (-8875 1750);
DISPLAY INVISIBLE (-8875 1750);
FORCEADD OFFPAGE..2
R 2
(-8675 1650);
FORCEPROP 2 LAST $XR1 28 
J 0
(-8989 1650);
DISPLAY 0.638298 (-8989 1650);
PAINT MONO (-8989 1650);
FORCEPROP 2 LAST $XR0 81 
J 0
(-8899 1650);
DISPLAY 0.638298 (-8899 1650);
PAINT MONO (-8899 1650);
FORCEPROP 2 LAST CDS_LIB standard
J 0
(-8675 1650);
DISPLAY INVISIBLE (-8675 1650);
FORCEPROP 1 LAST OFFPAGE TRUE
J 2
(-9000 1525);
DISPLAY 0.872340 (-9000 1525);
PAINT GREEN (-9000 1525);
DISPLAY INVISIBLE (-9000 1525);
FORCEPROP 1 LAST COMMENT_BODY TRUE
J 2
(-8630 1555);
DISPLAY 0.872340 (-8630 1555);
PAINT GREEN (-8630 1555);
DISPLAY INVISIBLE (-8630 1555);
FORCEPROP 2 LAST PATH I323
J 0
(-8875 1700);
DISPLAY 1.021277 (-8875 1700);
DISPLAY INVISIBLE (-8875 1700);
FORCEADD OFFPAGE..2
R 2
(-8675 1600);
FORCEPROP 2 LAST $XR1 28 
J 0
(-8989 1600);
DISPLAY 0.638298 (-8989 1600);
PAINT MONO (-8989 1600);
FORCEPROP 2 LAST $XR0 81 
J 0
(-8899 1600);
DISPLAY 0.638298 (-8899 1600);
PAINT MONO (-8899 1600);
FORCEPROP 2 LAST CDS_LIB standard
J 0
(-8675 1600);
DISPLAY INVISIBLE (-8675 1600);
FORCEPROP 1 LAST OFFPAGE TRUE
J 2
(-9000 1475);
DISPLAY 0.872340 (-9000 1475);
PAINT GREEN (-9000 1475);
DISPLAY INVISIBLE (-9000 1475);
FORCEPROP 1 LAST COMMENT_BODY TRUE
J 2
(-8630 1505);
DISPLAY 0.872340 (-8630 1505);
PAINT GREEN (-8630 1505);
DISPLAY INVISIBLE (-8630 1505);
FORCEPROP 2 LAST PATH I324
J 0
(-8875 1650);
DISPLAY 1.021277 (-8875 1650);
DISPLAY INVISIBLE (-8875 1650);
FORCEADD OFFPAGE..2
R 2
(-8675 1550);
FORCEPROP 2 LAST $XR1 28 
J 0
(-8989 1550);
DISPLAY 0.638298 (-8989 1550);
PAINT MONO (-8989 1550);
FORCEPROP 2 LAST $XR0 81 
J 0
(-8899 1550);
DISPLAY 0.638298 (-8899 1550);
PAINT MONO (-8899 1550);
FORCEPROP 2 LAST CDS_LIB standard
J 0
(-8675 1550);
DISPLAY INVISIBLE (-8675 1550);
FORCEPROP 1 LAST OFFPAGE TRUE
J 2
(-9000 1425);
DISPLAY 0.872340 (-9000 1425);
PAINT GREEN (-9000 1425);
DISPLAY INVISIBLE (-9000 1425);
FORCEPROP 1 LAST COMMENT_BODY TRUE
J 2
(-8630 1455);
DISPLAY 0.872340 (-8630 1455);
PAINT GREEN (-8630 1455);
DISPLAY INVISIBLE (-8630 1455);
FORCEPROP 2 LAST PATH I325
J 0
(-8875 1600);
DISPLAY 1.021277 (-8875 1600);
DISPLAY INVISIBLE (-8875 1600);
FORCEADD OFFPAGE..2
R 2
(-8675 1500);
FORCEPROP 2 LAST $XR0 28 
J 0
(-8899 1500);
DISPLAY 0.638298 (-8899 1500);
PAINT MONO (-8899 1500);
FORCEPROP 2 LAST CDS_LIB standard
J 0
(-8675 1500);
DISPLAY INVISIBLE (-8675 1500);
FORCEPROP 1 LAST OFFPAGE TRUE
J 2
(-9000 1375);
DISPLAY 0.872340 (-9000 1375);
PAINT GREEN (-9000 1375);
DISPLAY INVISIBLE (-9000 1375);
FORCEPROP 1 LAST COMMENT_BODY TRUE
J 2
(-8630 1405);
DISPLAY 0.872340 (-8630 1405);
PAINT GREEN (-8630 1405);
DISPLAY INVISIBLE (-8630 1405);
FORCEPROP 2 LAST PATH I326
J 0
(-8875 1550);
DISPLAY 1.021277 (-8875 1550);
DISPLAY INVISIBLE (-8875 1550);
FORCEADD OFFPAGE..2
R 2
(-8675 1450);
FORCEPROP 2 LAST $XR0 28 
J 0
(-8899 1450);
DISPLAY 0.638298 (-8899 1450);
PAINT MONO (-8899 1450);
FORCEPROP 2 LAST CDS_LIB standard
J 0
(-8675 1450);
DISPLAY INVISIBLE (-8675 1450);
FORCEPROP 1 LAST OFFPAGE TRUE
J 2
(-9000 1325);
DISPLAY 0.872340 (-9000 1325);
PAINT GREEN (-9000 1325);
DISPLAY INVISIBLE (-9000 1325);
FORCEPROP 1 LAST COMMENT_BODY TRUE
J 2
(-8630 1355);
DISPLAY 0.872340 (-8630 1355);
PAINT GREEN (-8630 1355);
DISPLAY INVISIBLE (-8630 1355);
FORCEPROP 2 LAST PATH I327
J 0
(-8875 1500);
DISPLAY 1.021277 (-8875 1500);
DISPLAY INVISIBLE (-8875 1500);
FORCEADD OFFPAGE..2
R 2
(-8675 1400);
FORCEPROP 2 LAST $XR1 80 
J 0
(-8989 1400);
DISPLAY 0.638298 (-8989 1400);
PAINT MONO (-8989 1400);
FORCEPROP 2 LAST $XR0 28 
J 0
(-8899 1400);
DISPLAY 0.638298 (-8899 1400);
PAINT MONO (-8899 1400);
FORCEPROP 2 LAST CDS_LIB standard
J 0
(-8675 1400);
DISPLAY INVISIBLE (-8675 1400);
FORCEPROP 1 LAST OFFPAGE TRUE
J 2
(-9000 1275);
DISPLAY 0.872340 (-9000 1275);
PAINT GREEN (-9000 1275);
DISPLAY INVISIBLE (-9000 1275);
FORCEPROP 1 LAST COMMENT_BODY TRUE
J 2
(-8630 1305);
DISPLAY 0.872340 (-8630 1305);
PAINT GREEN (-8630 1305);
DISPLAY INVISIBLE (-8630 1305);
FORCEPROP 2 LAST PATH I328
J 0
(-8875 1450);
DISPLAY 1.021277 (-8875 1450);
DISPLAY INVISIBLE (-8875 1450);
FORCEADD Q_RES..1
(-7700 1350);
FORCEPROP 1 LAST LOCATION R451
J 0
(-7900 1350);
DISPLAY 0.489362 (-7900 1350);
PAINT SKYBLUE (-7900 1350);
FORCEPROP 0 LAST $SEC 1
J 0
(-7875 1400);
DISPLAY 0.680851 (-7875 1400);
PAINT MONO (-7875 1400);
DISPLAY INVISIBLE (-7875 1400);
FORCEPROP 0 LAST CDS_SEC 1
J 0
(-7875 1400);
DISPLAY 1.021277 (-7875 1400);
DISPLAY INVISIBLE (-7875 1400);
FORCEPROP 1 LASTPIN (-7800 1350) $PN 1
J 0
(-7788 1362);
DISPLAY 0.489362 (-7788 1362);
PAINT MONO (-7788 1362);
FORCEPROP 1 LASTPIN (-7600 1350) $PN 2
J 0
(-7638 1362);
DISPLAY 0.489362 (-7638 1362);
PAINT MONO (-7638 1362);
FORCEPROP 1 LAST VALUE 4.7K
J 0
(-7600 1350);
DISPLAY 0.489362 (-7600 1350);
PAINT SKYBLUE (-7600 1350);
FORCEPROP 2 LAST CDS_LIB pure_quanta
J 0
(-7700 1350);
DISPLAY INVISIBLE (-7700 1350);
FORCEPROP 1 LAST PATH I329
J 0
(-7750 1500);
DISPLAY 0.978723 (-7750 1500);
PAINT WHITE (-7750 1500);
DISPLAY INVISIBLE (-7750 1500);
FORCEPROP 1 LAST WATTAGE 1/16W
J 2
(-7725 1200);
DISPLAY 0.510638 (-7725 1200);
PAINT SKYBLUE (-7725 1200);
DISPLAY INVISIBLE (-7725 1200);
FORCEPROP 1 LAST MATERIAL CHIP
J 0
(-7600 1325);
DISPLAY 0.489362 (-7600 1325);
PAINT SKYBLUE (-7600 1325);
DISPLAY INVISIBLE (-7600 1325);
FORCEPROP 1 LAST TOLERANCE 5%
J 0
(-7575 1350);
DISPLAY 0.510638 (-7575 1350);
PAINT SKYBLUE (-7575 1350);
DISPLAY INVISIBLE (-7575 1350);
FORCEPROP 1 LAST PART_NUMBER TMP_QCS24702JB38
J 0
(-7750 1450);
DISPLAY 0.510638 (-7750 1450);
PAINT SKYBLUE (-7750 1450);
DISPLAY INVISIBLE (-7750 1450);
FORCEPROP 1 LAST PACK_TYPE 0402LF
J 0
(-7450 1200);
DISPLAY 0.510638 (-7450 1200);
PAINT SKYBLUE (-7450 1200);
DISPLAY INVISIBLE (-7450 1200);
FORCEADD Q_RES..1
(-7700 1300);
FORCEPROP 1 LAST LOCATION R452
J 0
(-7900 1300);
DISPLAY 0.489362 (-7900 1300);
PAINT SKYBLUE (-7900 1300);
FORCEPROP 0 LAST $SEC 1
J 0
(-7875 1350);
DISPLAY 0.680851 (-7875 1350);
PAINT MONO (-7875 1350);
DISPLAY INVISIBLE (-7875 1350);
FORCEPROP 0 LAST CDS_SEC 1
J 0
(-7875 1350);
DISPLAY 1.021277 (-7875 1350);
DISPLAY INVISIBLE (-7875 1350);
FORCEPROP 1 LASTPIN (-7800 1300) $PN 1
J 0
(-7788 1312);
DISPLAY 0.489362 (-7788 1312);
PAINT MONO (-7788 1312);
FORCEPROP 1 LASTPIN (-7600 1300) $PN 2
J 0
(-7638 1312);
DISPLAY 0.489362 (-7638 1312);
PAINT MONO (-7638 1312);
FORCEPROP 1 LAST VALUE 4.7K
J 0
(-7600 1300);
DISPLAY 0.489362 (-7600 1300);
PAINT SKYBLUE (-7600 1300);
FORCEPROP 2 LAST CDS_LIB pure_quanta
J 0
(-7700 1300);
DISPLAY INVISIBLE (-7700 1300);
FORCEPROP 1 LAST PATH I335
J 0
(-7750 1450);
DISPLAY 0.978723 (-7750 1450);
PAINT WHITE (-7750 1450);
DISPLAY INVISIBLE (-7750 1450);
FORCEPROP 1 LAST WATTAGE 1/16W
J 2
(-7725 1150);
DISPLAY 0.510638 (-7725 1150);
PAINT SKYBLUE (-7725 1150);
DISPLAY INVISIBLE (-7725 1150);
FORCEPROP 1 LAST MATERIAL CHIP
J 0
(-7600 1275);
DISPLAY 0.489362 (-7600 1275);
PAINT SKYBLUE (-7600 1275);
DISPLAY INVISIBLE (-7600 1275);
FORCEPROP 1 LAST TOLERANCE 5%
J 0
(-7575 1300);
DISPLAY 0.510638 (-7575 1300);
PAINT SKYBLUE (-7575 1300);
DISPLAY INVISIBLE (-7575 1300);
FORCEPROP 1 LAST PART_NUMBER TMP_QCS24702JB38
J 0
(-7750 1400);
DISPLAY 0.510638 (-7750 1400);
PAINT SKYBLUE (-7750 1400);
DISPLAY INVISIBLE (-7750 1400);
FORCEPROP 1 LAST PACK_TYPE 0402LF
J 0
(-7450 1150);
DISPLAY 0.510638 (-7450 1150);
PAINT SKYBLUE (-7450 1150);
DISPLAY INVISIBLE (-7450 1150);
FORCEADD OFFPAGE..2
R 2
(-8675 1250);
FORCEPROP 2 LAST $XR1 28 
J 0
(-8989 1250);
DISPLAY 0.638298 (-8989 1250);
PAINT MONO (-8989 1250);
FORCEPROP 2 LAST $XR0 81 
J 0
(-8899 1250);
DISPLAY 0.638298 (-8899 1250);
PAINT MONO (-8899 1250);
FORCEPROP 2 LAST CDS_LIB standard
J 0
(-8675 1250);
DISPLAY INVISIBLE (-8675 1250);
FORCEPROP 1 LAST OFFPAGE TRUE
J 2
(-9000 1125);
DISPLAY 0.872340 (-9000 1125);
PAINT GREEN (-9000 1125);
DISPLAY INVISIBLE (-9000 1125);
FORCEPROP 1 LAST COMMENT_BODY TRUE
J 2
(-8630 1155);
DISPLAY 0.872340 (-8630 1155);
PAINT GREEN (-8630 1155);
DISPLAY INVISIBLE (-8630 1155);
FORCEPROP 2 LAST PATH I337
J 0
(-8625 1325);
DISPLAY 1.021277 (-8625 1325);
DISPLAY INVISIBLE (-8625 1325);
FORCEADD OFFPAGE..2
R 2
(-8675 1350);
FORCEPROP 2 LAST $XR1 80 
J 0
(-8989 1350);
DISPLAY 0.638298 (-8989 1350);
PAINT MONO (-8989 1350);
FORCEPROP 2 LAST $XR0 28 
J 0
(-8899 1350);
DISPLAY 0.638298 (-8899 1350);
PAINT MONO (-8899 1350);
FORCEPROP 2 LAST CDS_LIB standard
J 0
(-8675 1350);
DISPLAY INVISIBLE (-8675 1350);
FORCEPROP 1 LAST OFFPAGE TRUE
J 2
(-9000 1225);
DISPLAY 0.872340 (-9000 1225);
PAINT GREEN (-9000 1225);
DISPLAY INVISIBLE (-9000 1225);
FORCEPROP 1 LAST COMMENT_BODY TRUE
J 2
(-8630 1255);
DISPLAY 0.872340 (-8630 1255);
PAINT GREEN (-8630 1255);
DISPLAY INVISIBLE (-8630 1255);
FORCEPROP 2 LAST PATH I338
J 0
(-8875 1400);
DISPLAY 1.021277 (-8875 1400);
DISPLAY INVISIBLE (-8875 1400);
FORCEADD OFFPAGE..2
R 2
(-8675 1300);
FORCEPROP 2 LAST $XR1 80 
J 0
(-8989 1300);
DISPLAY 0.638298 (-8989 1300);
PAINT MONO (-8989 1300);
FORCEPROP 2 LAST $XR0 28 
J 0
(-8899 1300);
DISPLAY 0.638298 (-8899 1300);
PAINT MONO (-8899 1300);
FORCEPROP 2 LAST CDS_LIB standard
J 0
(-8675 1300);
DISPLAY INVISIBLE (-8675 1300);
FORCEPROP 1 LAST OFFPAGE TRUE
J 2
(-9000 1175);
DISPLAY 0.872340 (-9000 1175);
PAINT GREEN (-9000 1175);
DISPLAY INVISIBLE (-9000 1175);
FORCEPROP 1 LAST COMMENT_BODY TRUE
J 2
(-8630 1205);
DISPLAY 0.872340 (-8630 1205);
PAINT GREEN (-8630 1205);
DISPLAY INVISIBLE (-8630 1205);
FORCEPROP 2 LAST PATH I339
J 0
(-8875 1350);
DISPLAY 1.021277 (-8875 1350);
DISPLAY INVISIBLE (-8875 1350);
FORCEADD Q_RES..1
R 1
(-7325 825);
FORCEPROP 1 LAST LOCATION R288
J 0
(-7300 750);
DISPLAY 0.489362 (-7300 750);
PAINT SKYBLUE (-7300 750);
FORCEPROP 2 LAST $SEC 1
J 0
(-7300 875);
DISPLAY 0.680851 (-7300 875);
PAINT MONO (-7300 875);
DISPLAY INVISIBLE (-7300 875);
FORCEPROP 2 LAST CDS_SEC 1
J 0
(-7300 875);
DISPLAY 1.021277 (-7300 875);
DISPLAY INVISIBLE (-7300 875);
FORCEPROP 1 LASTPIN (-7325 725) $PN 1
R 1
J 0
(-7337 737);
DISPLAY 0.489362 (-7337 737);
PAINT MONO (-7337 737);
FORCEPROP 1 LASTPIN (-7325 925) $PN 2
R 1
J 0
(-7337 887);
DISPLAY 0.489362 (-7337 887);
PAINT MONO (-7337 887);
FORCEPROP 1 LAST MATERIAL EMPTY
J 0
(-7300 850);
DISPLAY 0.489362 (-7300 850);
PAINT RED (-7300 850);
FORCEPROP 1 LAST VALUE 4.7K
J 0
(-7300 800);
DISPLAY 0.489362 (-7300 800);
PAINT SKYBLUE (-7300 800);
FORCEPROP 2 LAST CDS_LIB pure_quanta
J 0
(-7325 825);
DISPLAY INVISIBLE (-7325 825);
FORCEPROP 1 LAST PATH I340
R 1
J 0
(-7475 775);
DISPLAY 0.978723 (-7475 775);
PAINT WHITE (-7475 775);
DISPLAY INVISIBLE (-7475 775);
FORCEPROP 1 LAST WATTAGE 1/16W
R 1
J 2
(-7175 800);
DISPLAY 0.978723 (-7175 800);
PAINT SKYBLUE (-7175 800);
DISPLAY INVISIBLE (-7175 800);
FORCEPROP 1 LAST TOLERANCE 5%
R 1
J 0
(-7225 825);
DISPLAY 0.978723 (-7225 825);
PAINT SKYBLUE (-7225 825);
DISPLAY INVISIBLE (-7225 825);
FORCEPROP 1 LAST PART_NUMBER TMP_QCS24702JB38
R 1
J 0
(-7425 775);
DISPLAY 0.978723 (-7425 775);
PAINT SKYBLUE (-7425 775);
DISPLAY INVISIBLE (-7425 775);
FORCEPROP 1 LAST PACK_TYPE 0402LF
R 1
J 0
(-7175 1075);
DISPLAY 0.978723 (-7175 1075);
PAINT SKYBLUE (-7175 1075);
DISPLAY INVISIBLE (-7175 1075);
FORCEADD UNIVERSAL_POWER..1
(-7325 1025);
FORCEPROP 3 LASTPIN (-7325 975) SIG_NAME PVDD18_S5_P0\g
J 0
(-7315 985);
DISPLAY 0.659574 (-7315 985);
PAINT MONO (-7315 985);
DISPLAY INVISIBLE (-7315 985);
FORCEPROP 1 LAST HDL_POWER PVDD18_S5_P0
J 1
(-7325 1075);
DISPLAY 0.489362 (-7325 1075);
PAINT GREEN (-7325 1075);
FORCEPROP 2 LAST CDS_LIB pure_quanta_power
J 0
(-7325 1025);
DISPLAY INVISIBLE (-7325 1025);
FORCEPROP 1 LAST PATH I341
J 0
(-7275 1050);
DISPLAY 0.872340 (-7275 1050);
PAINT AQUA (-7275 1050);
DISPLAY INVISIBLE (-7275 1050);
FORCEADD Q_RES..1
R 1
(-7550 825);
FORCEPROP 1 LAST LOCATION R276
J 0
(-7525 750);
DISPLAY 0.489362 (-7525 750);
PAINT SKYBLUE (-7525 750);
FORCEPROP 2 LAST $SEC 1
J 0
(-7525 875);
DISPLAY 0.680851 (-7525 875);
PAINT MONO (-7525 875);
DISPLAY INVISIBLE (-7525 875);
FORCEPROP 2 LAST CDS_SEC 1
J 0
(-7525 875);
DISPLAY 1.021277 (-7525 875);
DISPLAY INVISIBLE (-7525 875);
FORCEPROP 1 LASTPIN (-7550 725) $PN 1
R 1
J 0
(-7562 737);
DISPLAY 0.489362 (-7562 737);
PAINT MONO (-7562 737);
FORCEPROP 1 LASTPIN (-7550 925) $PN 2
R 1
J 0
(-7562 887);
DISPLAY 0.489362 (-7562 887);
PAINT MONO (-7562 887);
FORCEPROP 1 LAST VALUE 4.7K
J 0
(-7525 800);
DISPLAY 0.489362 (-7525 800);
PAINT SKYBLUE (-7525 800);
FORCEPROP 1 LAST MATERIAL CHIP
J 0
(-7525 850);
DISPLAY 0.489362 (-7525 850);
PAINT SKYBLUE (-7525 850);
FORCEPROP 1 LAST PACK_TYPE 0402LF
R 1
J 0
(-7400 1075);
DISPLAY 0.978723 (-7400 1075);
PAINT SKYBLUE (-7400 1075);
DISPLAY INVISIBLE (-7400 1075);
FORCEPROP 1 LAST PART_NUMBER TMP_QCS24702JB38
R 1
J 0
(-7650 775);
DISPLAY 0.978723 (-7650 775);
PAINT SKYBLUE (-7650 775);
DISPLAY INVISIBLE (-7650 775);
FORCEPROP 1 LAST TOLERANCE 5%
R 1
J 0
(-7450 825);
DISPLAY 0.978723 (-7450 825);
PAINT SKYBLUE (-7450 825);
DISPLAY INVISIBLE (-7450 825);
FORCEPROP 1 LAST WATTAGE 1/16W
R 1
J 2
(-7400 800);
DISPLAY 0.978723 (-7400 800);
PAINT SKYBLUE (-7400 800);
DISPLAY INVISIBLE (-7400 800);
FORCEPROP 1 LAST PATH I342
R 1
J 0
(-7700 775);
DISPLAY 0.978723 (-7700 775);
PAINT WHITE (-7700 775);
DISPLAY INVISIBLE (-7700 775);
FORCEPROP 2 LAST CDS_LIB pure_quanta
J 0
(-7550 825);
DISPLAY INVISIBLE (-7550 825);
FORCEADD UNIVERSAL_GND..1
(-7325 325);
FORCEPROP 3 LASTPIN (-7325 375) SIG_NAME GND\g
J 0
(-7315 385);
DISPLAY 0.659574 (-7315 385);
PAINT MONO (-7315 385);
DISPLAY INVISIBLE (-7315 385);
FORCEPROP 2 LAST CDS_LIB pure_quanta_power
J 0
(-7325 325);
DISPLAY INVISIBLE (-7325 325);
FORCEPROP 1 LAST PATH I343
J 0
(-7250 325);
DISPLAY 0.872340 (-7250 325);
PAINT AQUA (-7250 325);
DISPLAY INVISIBLE (-7250 325);
FORCEPROP 1 LAST HDL_POWER GND
J 1
(-7300 250);
DISPLAY 0.872340 (-7300 250);
PAINT GREEN (-7300 250);
DISPLAY INVISIBLE (-7300 250);
FORCEADD Q_RES..1
R 1
(-7325 475);
FORCEPROP 1 LAST LOCATION R440
J 0
(-7300 400);
DISPLAY 0.489362 (-7300 400);
PAINT SKYBLUE (-7300 400);
FORCEPROP 2 LAST $SEC 1
J 0
(-7300 525);
DISPLAY 0.680851 (-7300 525);
PAINT MONO (-7300 525);
DISPLAY INVISIBLE (-7300 525);
FORCEPROP 2 LAST CDS_SEC 1
J 0
(-7300 525);
DISPLAY 1.021277 (-7300 525);
DISPLAY INVISIBLE (-7300 525);
FORCEPROP 1 LASTPIN (-7325 375) $PN 1
R 1
J 0
(-7337 387);
DISPLAY 0.489362 (-7337 387);
PAINT MONO (-7337 387);
FORCEPROP 1 LASTPIN (-7325 575) $PN 2
R 1
J 0
(-7337 537);
DISPLAY 0.489362 (-7337 537);
PAINT MONO (-7337 537);
FORCEPROP 1 LAST MATERIAL EMPTY
J 0
(-7300 500);
DISPLAY 0.489362 (-7300 500);
PAINT RED (-7300 500);
FORCEPROP 1 LAST VALUE 4.7K
J 0
(-7300 450);
DISPLAY 0.489362 (-7300 450);
PAINT SKYBLUE (-7300 450);
FORCEPROP 2 LAST CDS_LIB pure_quanta
J 0
(-7325 475);
DISPLAY INVISIBLE (-7325 475);
FORCEPROP 1 LAST PATH I344
R 1
J 0
(-7475 425);
DISPLAY 0.978723 (-7475 425);
PAINT WHITE (-7475 425);
DISPLAY INVISIBLE (-7475 425);
FORCEPROP 1 LAST WATTAGE 1/16W
R 1
J 2
(-7175 450);
DISPLAY 0.978723 (-7175 450);
PAINT SKYBLUE (-7175 450);
DISPLAY INVISIBLE (-7175 450);
FORCEPROP 1 LAST TOLERANCE 5%
R 1
J 0
(-7225 475);
DISPLAY 0.978723 (-7225 475);
PAINT SKYBLUE (-7225 475);
DISPLAY INVISIBLE (-7225 475);
FORCEPROP 1 LAST PART_NUMBER TMP_QCS24702JB38
R 1
J 0
(-7425 425);
DISPLAY 0.978723 (-7425 425);
PAINT SKYBLUE (-7425 425);
DISPLAY INVISIBLE (-7425 425);
FORCEPROP 1 LAST PACK_TYPE 0402LF
R 1
J 0
(-7175 725);
DISPLAY 0.978723 (-7175 725);
PAINT SKYBLUE (-7175 725);
DISPLAY INVISIBLE (-7175 725);
FORCEADD Q_RES..1
R 1
(-7550 475);
FORCEPROP 1 LAST LOCATION R287
J 0
(-7525 400);
DISPLAY 0.489362 (-7525 400);
PAINT SKYBLUE (-7525 400);
FORCEPROP 2 LAST $SEC 1
J 0
(-7525 525);
DISPLAY 0.680851 (-7525 525);
PAINT MONO (-7525 525);
DISPLAY INVISIBLE (-7525 525);
FORCEPROP 2 LAST CDS_SEC 1
J 0
(-7525 525);
DISPLAY 1.021277 (-7525 525);
DISPLAY INVISIBLE (-7525 525);
FORCEPROP 1 LASTPIN (-7550 375) $PN 1
R 1
J 0
(-7562 387);
DISPLAY 0.489362 (-7562 387);
PAINT MONO (-7562 387);
FORCEPROP 1 LASTPIN (-7550 575) $PN 2
R 1
J 0
(-7562 537);
DISPLAY 0.489362 (-7562 537);
PAINT MONO (-7562 537);
FORCEPROP 1 LAST MATERIAL EMPTY
J 0
(-7525 500);
DISPLAY 0.489362 (-7525 500);
PAINT RED (-7525 500);
FORCEPROP 1 LAST VALUE 4.7K
J 0
(-7525 450);
DISPLAY 0.489362 (-7525 450);
PAINT SKYBLUE (-7525 450);
FORCEPROP 2 LAST CDS_LIB pure_quanta
J 0
(-7550 475);
DISPLAY INVISIBLE (-7550 475);
FORCEPROP 1 LAST PATH I345
R 1
J 0
(-7700 425);
DISPLAY 0.978723 (-7700 425);
PAINT WHITE (-7700 425);
DISPLAY INVISIBLE (-7700 425);
FORCEPROP 1 LAST WATTAGE 1/16W
R 1
J 2
(-7400 450);
DISPLAY 0.978723 (-7400 450);
PAINT SKYBLUE (-7400 450);
DISPLAY INVISIBLE (-7400 450);
FORCEPROP 1 LAST TOLERANCE 5%
R 1
J 0
(-7450 475);
DISPLAY 0.978723 (-7450 475);
PAINT SKYBLUE (-7450 475);
DISPLAY INVISIBLE (-7450 475);
FORCEPROP 1 LAST PART_NUMBER TMP_QCS24702JB38
R 1
J 0
(-7650 425);
DISPLAY 0.978723 (-7650 425);
PAINT SKYBLUE (-7650 425);
DISPLAY INVISIBLE (-7650 425);
FORCEPROP 1 LAST PACK_TYPE 0402LF
R 1
J 0
(-7400 725);
DISPLAY 0.978723 (-7400 725);
PAINT SKYBLUE (-7400 725);
DISPLAY INVISIBLE (-7400 725);
FORCEADD UNIVERSAL_GND..1
(-7550 325);
FORCEPROP 3 LASTPIN (-7550 375) SIG_NAME GND\g
J 0
(-7540 385);
DISPLAY 0.659574 (-7540 385);
PAINT MONO (-7540 385);
DISPLAY INVISIBLE (-7540 385);
FORCEPROP 2 LAST CDS_LIB pure_quanta_power
J 0
(-7550 325);
DISPLAY INVISIBLE (-7550 325);
FORCEPROP 1 LAST PATH I346
J 0
(-7475 325);
DISPLAY 0.872340 (-7475 325);
PAINT AQUA (-7475 325);
DISPLAY INVISIBLE (-7475 325);
FORCEPROP 1 LAST HDL_POWER GND
J 1
(-7525 250);
DISPLAY 0.872340 (-7525 250);
PAINT GREEN (-7525 250);
DISPLAY INVISIBLE (-7525 250);
FORCEADD Q_RES..1
R 1
(-7825 850);
FORCEPROP 1 LAST LOCATION R581
J 0
(-7800 775);
DISPLAY 0.489362 (-7800 775);
PAINT SKYBLUE (-7800 775);
FORCEPROP 0 LAST $SEC 1
R 1
J 0
(-7800 900);
DISPLAY 0.680851 (-7800 900);
PAINT MONO (-7800 900);
DISPLAY INVISIBLE (-7800 900);
FORCEPROP 0 LAST CDS_SEC 1
R 1
J 0
(-7800 900);
DISPLAY 1.021277 (-7800 900);
DISPLAY INVISIBLE (-7800 900);
FORCEPROP 1 LASTPIN (-7825 750) $PN 1
R 1
J 0
(-7837 762);
DISPLAY 0.489362 (-7837 762);
PAINT MONO (-7837 762);
FORCEPROP 1 LASTPIN (-7825 950) $PN 2
R 1
J 0
(-7837 912);
DISPLAY 0.489362 (-7837 912);
PAINT MONO (-7837 912);
FORCEPROP 1 LAST VALUE 4.7K
J 0
(-7800 825);
DISPLAY 0.489362 (-7800 825);
PAINT SKYBLUE (-7800 825);
FORCEPROP 1 LAST MATERIAL EMPTY
J 0
(-7800 875);
DISPLAY 0.489362 (-7800 875);
PAINT RED (-7800 875);
FORCEPROP 2 LAST CDS_LIB pure_quanta
J 0
(-7825 850);
DISPLAY INVISIBLE (-7825 850);
FORCEPROP 1 LAST PATH I347
R 1
J 0
(-7975 800);
DISPLAY 0.978723 (-7975 800);
PAINT WHITE (-7975 800);
DISPLAY INVISIBLE (-7975 800);
FORCEPROP 1 LAST WATTAGE 1/16W
R 1
J 2
(-7675 825);
DISPLAY 0.978723 (-7675 825);
PAINT SKYBLUE (-7675 825);
DISPLAY INVISIBLE (-7675 825);
FORCEPROP 1 LAST TOLERANCE 5%
R 1
J 0
(-7725 850);
DISPLAY 0.978723 (-7725 850);
PAINT SKYBLUE (-7725 850);
DISPLAY INVISIBLE (-7725 850);
FORCEPROP 1 LAST PART_NUMBER TMP_QCS24702JB38
R 1
J 0
(-7925 800);
DISPLAY 0.978723 (-7925 800);
PAINT SKYBLUE (-7925 800);
DISPLAY INVISIBLE (-7925 800);
FORCEPROP 1 LAST PACK_TYPE 0402LF
R 1
J 0
(-7675 1100);
DISPLAY 0.978723 (-7675 1100);
PAINT SKYBLUE (-7675 1100);
DISPLAY INVISIBLE (-7675 1100);
FORCEADD Q_RES..1
R 1
(-7825 500);
FORCEPROP 1 LAST LOCATION R582
J 0
(-7800 400);
DISPLAY 0.489362 (-7800 400);
PAINT SKYBLUE (-7800 400);
FORCEPROP 0 LAST $SEC 1
R 1
J 0
(-7800 550);
DISPLAY 0.680851 (-7800 550);
PAINT MONO (-7800 550);
DISPLAY INVISIBLE (-7800 550);
FORCEPROP 0 LAST CDS_SEC 1
R 1
J 0
(-7800 550);
DISPLAY 1.021277 (-7800 550);
DISPLAY INVISIBLE (-7800 550);
FORCEPROP 1 LASTPIN (-7825 400) $PN 1
R 1
J 0
(-7837 412);
DISPLAY 0.489362 (-7837 412);
PAINT MONO (-7837 412);
FORCEPROP 1 LASTPIN (-7825 600) $PN 2
R 1
J 0
(-7837 562);
DISPLAY 0.489362 (-7837 562);
PAINT MONO (-7837 562);
FORCEPROP 1 LAST MATERIAL EMPTY
J 0
(-7800 525);
DISPLAY 0.489362 (-7800 525);
PAINT RED (-7800 525);
FORCEPROP 1 LAST VALUE 4.7K
J 0
(-7800 475);
DISPLAY 0.489362 (-7800 475);
PAINT SKYBLUE (-7800 475);
FORCEPROP 2 LAST CDS_LIB pure_quanta
R 1
J 0
(-7825 500);
DISPLAY INVISIBLE (-7825 500);
FORCEPROP 1 LAST PATH I348
R 1
J 0
(-7975 450);
DISPLAY 0.978723 (-7975 450);
PAINT WHITE (-7975 450);
DISPLAY INVISIBLE (-7975 450);
FORCEPROP 1 LAST WATTAGE 1/16W
R 1
J 2
(-7675 475);
DISPLAY 0.978723 (-7675 475);
PAINT SKYBLUE (-7675 475);
DISPLAY INVISIBLE (-7675 475);
FORCEPROP 1 LAST TOLERANCE 5%
R 1
J 0
(-7725 500);
DISPLAY 0.978723 (-7725 500);
PAINT SKYBLUE (-7725 500);
DISPLAY INVISIBLE (-7725 500);
FORCEPROP 1 LAST PART_NUMBER TMP_QCS24702JB38
R 1
J 0
(-7925 450);
DISPLAY 0.978723 (-7925 450);
PAINT SKYBLUE (-7925 450);
DISPLAY INVISIBLE (-7925 450);
FORCEPROP 1 LAST PACK_TYPE 0402LF
R 1
J 0
(-7675 750);
DISPLAY 0.978723 (-7675 750);
PAINT SKYBLUE (-7675 750);
DISPLAY INVISIBLE (-7675 750);
FORCEADD UNIVERSAL_GND..1
(-7825 350);
FORCEPROP 3 LASTPIN (-7825 400) SIG_NAME GND\g
J 0
(-7815 410);
DISPLAY 0.659574 (-7815 410);
PAINT MONO (-7815 410);
DISPLAY INVISIBLE (-7815 410);
FORCEPROP 2 LAST CDS_LIB pure_quanta_power
J 0
(-7825 350);
DISPLAY INVISIBLE (-7825 350);
FORCEPROP 1 LAST PATH I349
J 0
(-7750 350);
DISPLAY 0.872340 (-7750 350);
PAINT AQUA (-7750 350);
DISPLAY INVISIBLE (-7750 350);
FORCEPROP 1 LAST HDL_POWER GND
J 1
(-7800 275);
DISPLAY 0.872340 (-7800 275);
PAINT GREEN (-7800 275);
DISPLAY INVISIBLE (-7800 275);
FORCEADD OFFPAGE..2
R 2
(-8700 625);
FORCEPROP 2 LAST $XR0 28 
J 0
(-8924 625);
DISPLAY 0.638298 (-8924 625);
PAINT MONO (-8924 625);
FORCEPROP 2 LAST CDS_LIB standard
J 0
(-8700 625);
DISPLAY INVISIBLE (-8700 625);
FORCEPROP 1 LAST OFFPAGE TRUE
J 2
(-9025 500);
DISPLAY 0.872340 (-9025 500);
PAINT GREEN (-9025 500);
DISPLAY INVISIBLE (-9025 500);
FORCEPROP 1 LAST COMMENT_BODY TRUE
J 2
(-8655 530);
DISPLAY 0.872340 (-8655 530);
PAINT GREEN (-8655 530);
DISPLAY INVISIBLE (-8655 530);
FORCEPROP 2 LAST PATH I350
J 0
(-8650 700);
DISPLAY 1.021277 (-8650 700);
DISPLAY INVISIBLE (-8650 700);
FORCEADD OFFPAGE..2
R 2
(-8700 725);
FORCEPROP 2 LAST $XR1 80 
J 0
(-9014 725);
DISPLAY 0.638298 (-9014 725);
PAINT MONO (-9014 725);
FORCEPROP 2 LAST $XR0 28 
J 0
(-8924 725);
DISPLAY 0.638298 (-8924 725);
PAINT MONO (-8924 725);
FORCEPROP 2 LAST CDS_LIB standard
J 0
(-8700 725);
DISPLAY INVISIBLE (-8700 725);
FORCEPROP 1 LAST OFFPAGE TRUE
J 2
(-9025 600);
DISPLAY 0.872340 (-9025 600);
PAINT GREEN (-9025 600);
DISPLAY INVISIBLE (-9025 600);
FORCEPROP 1 LAST COMMENT_BODY TRUE
J 2
(-8655 630);
DISPLAY 0.872340 (-8655 630);
PAINT GREEN (-8655 630);
DISPLAY INVISIBLE (-8655 630);
FORCEPROP 2 LAST PATH I351
J 0
(-8900 775);
DISPLAY 1.021277 (-8900 775);
DISPLAY INVISIBLE (-8900 775);
FORCEADD OFFPAGE..2
R 2
(-8700 675);
FORCEPROP 2 LAST $XR1 28 
J 0
(-9014 675);
DISPLAY 0.638298 (-9014 675);
PAINT MONO (-9014 675);
FORCEPROP 2 LAST $XR0 80 
J 0
(-8924 675);
DISPLAY 0.638298 (-8924 675);
PAINT MONO (-8924 675);
FORCEPROP 2 LAST CDS_LIB standard
J 0
(-8700 675);
DISPLAY INVISIBLE (-8700 675);
FORCEPROP 1 LAST OFFPAGE TRUE
J 2
(-9025 550);
DISPLAY 0.872340 (-9025 550);
PAINT GREEN (-9025 550);
DISPLAY INVISIBLE (-9025 550);
FORCEPROP 1 LAST COMMENT_BODY TRUE
J 2
(-8655 580);
DISPLAY 0.872340 (-8655 580);
PAINT GREEN (-8655 580);
DISPLAY INVISIBLE (-8655 580);
FORCEPROP 2 LAST PATH I352
J 0
(-8900 725);
DISPLAY 1.021277 (-8900 725);
DISPLAY INVISIBLE (-8900 725);
FORCEADD OFFPAGE..4
R 2
(-7225 3100);
FORCEPROP 2 LAST $XR0 34 
J 0
(-7476 3100);
DISPLAY 0.638298 (-7476 3100);
PAINT MONO (-7476 3100);
FORCEPROP 2 LAST CDS_LIB standard
J 0
(-7225 3100);
DISPLAY INVISIBLE (-7225 3100);
FORCEPROP 1 LAST OFFPAGE TRUE
J 2
(-7550 2975);
DISPLAY 0.872340 (-7550 2975);
PAINT GREEN (-7550 2975);
DISPLAY INVISIBLE (-7550 2975);
FORCEPROP 1 LAST COMMENT_BODY TRUE
J 2
(-7200 3000);
DISPLAY 0.872340 (-7200 3000);
PAINT GREEN (-7200 3000);
DISPLAY INVISIBLE (-7200 3000);
FORCEPROP 2 LAST PATH I355
J 0
(-7175 3175);
DISPLAY 0.680851 (-7175 3175);
DISPLAY INVISIBLE (-7175 3175);
FORCEADD OFFPAGE..4
R 2
(-7225 3150);
FORCEPROP 2 LAST $XR0 34 
J 0
(-7476 3150);
DISPLAY 0.638298 (-7476 3150);
PAINT MONO (-7476 3150);
FORCEPROP 2 LAST CDS_LIB standard
J 0
(-7225 3150);
DISPLAY INVISIBLE (-7225 3150);
FORCEPROP 1 LAST OFFPAGE TRUE
J 2
(-7550 3025);
DISPLAY 0.872340 (-7550 3025);
PAINT GREEN (-7550 3025);
DISPLAY INVISIBLE (-7550 3025);
FORCEPROP 1 LAST COMMENT_BODY TRUE
J 2
(-7200 3050);
DISPLAY 0.872340 (-7200 3050);
PAINT GREEN (-7200 3050);
DISPLAY INVISIBLE (-7200 3050);
FORCEPROP 2 LAST PATH I356
J 0
(-7175 3225);
DISPLAY 0.680851 (-7175 3225);
DISPLAY INVISIBLE (-7175 3225);
FORCEADD Q_RES..1
(-2050 4100);
FORCEPROP 1 LAST LOCATION R256
J 0
(-2250 4100);
DISPLAY 0.489362 (-2250 4100);
PAINT SKYBLUE (-2250 4100);
FORCEPROP 0 LAST $SEC 1
J 0
(-2200 4150);
DISPLAY 0.680851 (-2200 4150);
PAINT MONO (-2200 4150);
DISPLAY INVISIBLE (-2200 4150);
FORCEPROP 0 LAST CDS_SEC 1
J 0
(-2200 4150);
DISPLAY 0.680851 (-2200 4150);
DISPLAY INVISIBLE (-2200 4150);
FORCEPROP 1 LASTPIN (-2150 4100) $PN 1
J 0
(-2138 4112);
DISPLAY 0.489362 (-2138 4112);
PAINT MONO (-2138 4112);
FORCEPROP 1 LASTPIN (-1950 4100) $PN 2
J 0
(-1988 4112);
DISPLAY 0.489362 (-1988 4112);
PAINT MONO (-1988 4112);
FORCEPROP 1 LAST VALUE 0
J 2
(-1925 4100);
DISPLAY 0.489362 (-1925 4100);
PAINT SKYBLUE (-1925 4100);
FORCEPROP 2 LAST CDS_LIB pure_quanta
J 0
(-2050 4100);
DISPLAY INVISIBLE (-2050 4100);
FORCEPROP 1 LAST PATH I357
J 0
(-2100 4250);
DISPLAY 0.978723 (-2100 4250);
PAINT WHITE (-2100 4250);
DISPLAY INVISIBLE (-2100 4250);
FORCEPROP 1 LAST WATTAGE 1/16W
J 2
(-1650 4025);
DISPLAY 0.489362 (-1650 4025);
PAINT SKYBLUE (-1650 4025);
DISPLAY INVISIBLE (-1650 4025);
FORCEPROP 1 LAST MATERIAL CHIP
J 0
(-1625 4025);
DISPLAY 0.489362 (-1625 4025);
PAINT SKYBLUE (-1625 4025);
DISPLAY INVISIBLE (-1625 4025);
FORCEPROP 1 LAST TOLERANCE 5%
J 0
(-2075 4025);
DISPLAY 0.489362 (-2075 4025);
PAINT SKYBLUE (-2075 4025);
DISPLAY INVISIBLE (-2075 4025);
FORCEPROP 1 LAST PART_NUMBER CS00002JB38
J 0
(-2025 4150);
DISPLAY 0.489362 (-2025 4150);
PAINT SKYBLUE (-2025 4150);
DISPLAY INVISIBLE (-2025 4150);
FORCEPROP 1 LAST PACK_TYPE 0402LF
J 0
(-2000 4025);
DISPLAY 0.489362 (-2000 4025);
PAINT SKYBLUE (-2000 4025);
DISPLAY INVISIBLE (-2000 4025);
FORCEADD Q_RES..1
(-2050 4150);
FORCEPROP 1 LAST LOCATION R206
J 0
(-2250 4150);
DISPLAY 0.489362 (-2250 4150);
PAINT SKYBLUE (-2250 4150);
FORCEPROP 0 LAST $SEC 1
J 0
(-2200 4200);
DISPLAY 0.680851 (-2200 4200);
PAINT MONO (-2200 4200);
DISPLAY INVISIBLE (-2200 4200);
FORCEPROP 0 LAST CDS_SEC 1
J 0
(-2200 4200);
DISPLAY 0.680851 (-2200 4200);
DISPLAY INVISIBLE (-2200 4200);
FORCEPROP 1 LASTPIN (-2150 4150) $PN 1
J 0
(-2138 4162);
DISPLAY 0.489362 (-2138 4162);
PAINT MONO (-2138 4162);
FORCEPROP 1 LASTPIN (-1950 4150) $PN 2
J 0
(-1988 4162);
DISPLAY 0.489362 (-1988 4162);
PAINT MONO (-1988 4162);
FORCEPROP 1 LAST VALUE 0
J 2
(-1925 4150);
DISPLAY 0.489362 (-1925 4150);
PAINT SKYBLUE (-1925 4150);
FORCEPROP 2 LAST CDS_LIB pure_quanta
J 0
(-2050 4150);
DISPLAY INVISIBLE (-2050 4150);
FORCEPROP 1 LAST PATH I358
J 0
(-2100 4300);
DISPLAY 0.978723 (-2100 4300);
PAINT WHITE (-2100 4300);
DISPLAY INVISIBLE (-2100 4300);
FORCEPROP 1 LAST WATTAGE 1/16W
J 2
(-1650 4075);
DISPLAY 0.489362 (-1650 4075);
PAINT SKYBLUE (-1650 4075);
DISPLAY INVISIBLE (-1650 4075);
FORCEPROP 1 LAST MATERIAL CHIP
J 0
(-1625 4075);
DISPLAY 0.489362 (-1625 4075);
PAINT SKYBLUE (-1625 4075);
DISPLAY INVISIBLE (-1625 4075);
FORCEPROP 1 LAST TOLERANCE 5%
J 0
(-2075 4075);
DISPLAY 0.489362 (-2075 4075);
PAINT SKYBLUE (-2075 4075);
DISPLAY INVISIBLE (-2075 4075);
FORCEPROP 1 LAST PART_NUMBER CS00002JB38
J 0
(-2025 4200);
DISPLAY 0.489362 (-2025 4200);
PAINT SKYBLUE (-2025 4200);
DISPLAY INVISIBLE (-2025 4200);
FORCEPROP 1 LAST PACK_TYPE 0402LF
J 0
(-2000 4075);
DISPLAY 0.489362 (-2000 4075);
PAINT SKYBLUE (-2000 4075);
DISPLAY INVISIBLE (-2000 4075);
FORCEADD OFFPAGE..2
(-1175 4150);
FORCEPROP 2 LAST $XR0 112 
J 0
(-986 4150);
DISPLAY 0.638298 (-986 4150);
PAINT MONO (-986 4150);
FORCEPROP 2 LAST CDS_LIB standard
J 0
(-1175 4150);
DISPLAY INVISIBLE (-1175 4150);
FORCEPROP 1 LAST OFFPAGE TRUE
J 0
(-850 4025);
DISPLAY 0.872340 (-850 4025);
PAINT GREEN (-850 4025);
DISPLAY INVISIBLE (-850 4025);
FORCEPROP 1 LAST COMMENT_BODY TRUE
J 0
(-1220 4055);
DISPLAY 0.872340 (-1220 4055);
PAINT GREEN (-1220 4055);
DISPLAY INVISIBLE (-1220 4055);
FORCEPROP 2 LAST PATH I359
J 0
(-975 4200);
DISPLAY 0.680851 (-975 4200);
DISPLAY INVISIBLE (-975 4200);
FORCEADD OFFPAGE..2
(-1175 4100);
FORCEPROP 2 LAST $XR0 112 
J 0
(-986 4100);
DISPLAY 0.638298 (-986 4100);
PAINT MONO (-986 4100);
FORCEPROP 2 LAST CDS_LIB standard
J 0
(-1175 4100);
DISPLAY INVISIBLE (-1175 4100);
FORCEPROP 1 LAST OFFPAGE TRUE
J 0
(-850 3975);
DISPLAY 0.872340 (-850 3975);
PAINT GREEN (-850 3975);
DISPLAY INVISIBLE (-850 3975);
FORCEPROP 1 LAST COMMENT_BODY TRUE
J 0
(-1220 4005);
DISPLAY 0.872340 (-1220 4005);
PAINT GREEN (-1220 4005);
DISPLAY INVISIBLE (-1220 4005);
FORCEPROP 2 LAST PATH I360
J 0
(-975 4150);
DISPLAY 0.680851 (-975 4150);
DISPLAY INVISIBLE (-975 4150);
FORCEADD OFFPAGE..2
(-1125 3850);
FORCEPROP 2 LAST $XR0 110 
J 0
(-936 3850);
DISPLAY 0.638298 (-936 3850);
PAINT MONO (-936 3850);
FORCEPROP 2 LAST CDS_LIB standard
J 0
(-1125 3850);
DISPLAY INVISIBLE (-1125 3850);
FORCEPROP 1 LAST OFFPAGE TRUE
J 0
(-800 3725);
DISPLAY 0.872340 (-800 3725);
PAINT GREEN (-800 3725);
DISPLAY INVISIBLE (-800 3725);
FORCEPROP 1 LAST COMMENT_BODY TRUE
J 0
(-1170 3755);
DISPLAY 0.872340 (-1170 3755);
PAINT GREEN (-1170 3755);
DISPLAY INVISIBLE (-1170 3755);
FORCEPROP 2 LAST PATH I361
J 0
(-925 3900);
DISPLAY 0.680851 (-925 3900);
DISPLAY INVISIBLE (-925 3900);
FORCEADD OFFPAGE..2
(-1125 3800);
FORCEPROP 2 LAST $XR0 110 
J 0
(-936 3800);
DISPLAY 0.638298 (-936 3800);
PAINT MONO (-936 3800);
FORCEPROP 2 LAST CDS_LIB standard
J 0
(-1125 3800);
DISPLAY INVISIBLE (-1125 3800);
FORCEPROP 1 LAST OFFPAGE TRUE
J 0
(-800 3675);
DISPLAY 0.872340 (-800 3675);
PAINT GREEN (-800 3675);
DISPLAY INVISIBLE (-800 3675);
FORCEPROP 1 LAST COMMENT_BODY TRUE
J 0
(-1170 3705);
DISPLAY 0.872340 (-1170 3705);
PAINT GREEN (-1170 3705);
DISPLAY INVISIBLE (-1170 3705);
FORCEPROP 2 LAST PATH I362
J 0
(-925 3850);
DISPLAY 0.680851 (-925 3850);
DISPLAY INVISIBLE (-925 3850);
FORCEADD Q_RES..1
(-2050 3800);
FORCEPROP 1 LAST LOCATION R746
J 0
(-2250 3800);
DISPLAY 0.489362 (-2250 3800);
PAINT SKYBLUE (-2250 3800);
FORCEPROP 0 LAST $SEC 1
J 0
(-2200 3850);
DISPLAY 0.680851 (-2200 3850);
PAINT MONO (-2200 3850);
DISPLAY INVISIBLE (-2200 3850);
FORCEPROP 0 LAST CDS_SEC 1
J 0
(-2200 3850);
DISPLAY 0.680851 (-2200 3850);
DISPLAY INVISIBLE (-2200 3850);
FORCEPROP 1 LASTPIN (-2150 3800) $PN 1
J 0
(-2138 3812);
DISPLAY 0.489362 (-2138 3812);
PAINT MONO (-2138 3812);
FORCEPROP 1 LASTPIN (-1950 3800) $PN 2
J 0
(-1988 3812);
DISPLAY 0.489362 (-1988 3812);
PAINT MONO (-1988 3812);
FORCEPROP 1 LAST VALUE 0
J 2
(-1925 3800);
DISPLAY 0.489362 (-1925 3800);
PAINT SKYBLUE (-1925 3800);
FORCEPROP 2 LAST CDS_LIB pure_quanta
J 0
(-2050 3800);
DISPLAY INVISIBLE (-2050 3800);
FORCEPROP 1 LAST PATH I363
J 0
(-2100 3950);
DISPLAY 0.978723 (-2100 3950);
PAINT WHITE (-2100 3950);
DISPLAY INVISIBLE (-2100 3950);
FORCEPROP 1 LAST WATTAGE 1/16W
J 2
(-1650 3725);
DISPLAY 0.489362 (-1650 3725);
PAINT SKYBLUE (-1650 3725);
DISPLAY INVISIBLE (-1650 3725);
FORCEPROP 1 LAST MATERIAL CHIP
J 0
(-1625 3725);
DISPLAY 0.489362 (-1625 3725);
PAINT SKYBLUE (-1625 3725);
DISPLAY INVISIBLE (-1625 3725);
FORCEPROP 1 LAST TOLERANCE 5%
J 0
(-2075 3725);
DISPLAY 0.489362 (-2075 3725);
PAINT SKYBLUE (-2075 3725);
DISPLAY INVISIBLE (-2075 3725);
FORCEPROP 1 LAST PART_NUMBER CS00002JB38
J 0
(-2025 3850);
DISPLAY 0.489362 (-2025 3850);
PAINT SKYBLUE (-2025 3850);
DISPLAY INVISIBLE (-2025 3850);
FORCEPROP 1 LAST PACK_TYPE 0402LF
J 0
(-2000 3725);
DISPLAY 0.489362 (-2000 3725);
PAINT SKYBLUE (-2000 3725);
DISPLAY INVISIBLE (-2000 3725);
FORCEADD Q_RES..1
(-2050 3850);
FORCEPROP 1 LAST LOCATION R636
J 0
(-2250 3850);
DISPLAY 0.489362 (-2250 3850);
PAINT SKYBLUE (-2250 3850);
FORCEPROP 0 LAST $SEC 1
J 0
(-2200 3900);
DISPLAY 0.680851 (-2200 3900);
PAINT MONO (-2200 3900);
DISPLAY INVISIBLE (-2200 3900);
FORCEPROP 0 LAST CDS_SEC 1
J 0
(-2200 3900);
DISPLAY 0.680851 (-2200 3900);
DISPLAY INVISIBLE (-2200 3900);
FORCEPROP 1 LASTPIN (-2150 3850) $PN 1
J 0
(-2138 3862);
DISPLAY 0.489362 (-2138 3862);
PAINT MONO (-2138 3862);
FORCEPROP 1 LASTPIN (-1950 3850) $PN 2
J 0
(-1988 3862);
DISPLAY 0.489362 (-1988 3862);
PAINT MONO (-1988 3862);
FORCEPROP 1 LAST VALUE 0
J 2
(-1925 3850);
DISPLAY 0.489362 (-1925 3850);
PAINT SKYBLUE (-1925 3850);
FORCEPROP 2 LAST CDS_LIB pure_quanta
J 0
(-2050 3850);
DISPLAY INVISIBLE (-2050 3850);
FORCEPROP 1 LAST PATH I364
J 0
(-2100 4000);
DISPLAY 0.978723 (-2100 4000);
PAINT WHITE (-2100 4000);
DISPLAY INVISIBLE (-2100 4000);
FORCEPROP 1 LAST WATTAGE 1/16W
J 2
(-1650 3775);
DISPLAY 0.489362 (-1650 3775);
PAINT SKYBLUE (-1650 3775);
DISPLAY INVISIBLE (-1650 3775);
FORCEPROP 1 LAST MATERIAL CHIP
J 0
(-1625 3775);
DISPLAY 0.489362 (-1625 3775);
PAINT SKYBLUE (-1625 3775);
DISPLAY INVISIBLE (-1625 3775);
FORCEPROP 1 LAST TOLERANCE 5%
J 0
(-2075 3775);
DISPLAY 0.489362 (-2075 3775);
PAINT SKYBLUE (-2075 3775);
DISPLAY INVISIBLE (-2075 3775);
FORCEPROP 1 LAST PART_NUMBER CS00002JB38
J 0
(-2025 3900);
DISPLAY 0.489362 (-2025 3900);
PAINT SKYBLUE (-2025 3900);
DISPLAY INVISIBLE (-2025 3900);
FORCEPROP 1 LAST PACK_TYPE 0402LF
J 0
(-2000 3775);
DISPLAY 0.489362 (-2000 3775);
PAINT SKYBLUE (-2000 3775);
DISPLAY INVISIBLE (-2000 3775);
FORCEADD OFFPAGE..2
(-1100 3550);
FORCEPROP 2 LAST $XR0 117 
J 0
(-911 3550);
DISPLAY 0.638298 (-911 3550);
PAINT MONO (-911 3550);
FORCEPROP 2 LAST CDS_LIB standard
J 0
(-1100 3550);
DISPLAY INVISIBLE (-1100 3550);
FORCEPROP 1 LAST OFFPAGE TRUE
J 0
(-775 3425);
DISPLAY 0.872340 (-775 3425);
PAINT GREEN (-775 3425);
DISPLAY INVISIBLE (-775 3425);
FORCEPROP 1 LAST COMMENT_BODY TRUE
J 0
(-1145 3455);
DISPLAY 0.872340 (-1145 3455);
PAINT GREEN (-1145 3455);
DISPLAY INVISIBLE (-1145 3455);
FORCEPROP 2 LAST PATH I365
J 0
(-900 3600);
DISPLAY 0.680851 (-900 3600);
DISPLAY INVISIBLE (-900 3600);
FORCEADD OFFPAGE..2
(-1100 3500);
FORCEPROP 2 LAST $XR0 117 
J 0
(-911 3500);
DISPLAY 0.638298 (-911 3500);
PAINT MONO (-911 3500);
FORCEPROP 2 LAST CDS_LIB standard
J 0
(-1100 3500);
DISPLAY INVISIBLE (-1100 3500);
FORCEPROP 1 LAST OFFPAGE TRUE
J 0
(-775 3375);
DISPLAY 0.872340 (-775 3375);
PAINT GREEN (-775 3375);
DISPLAY INVISIBLE (-775 3375);
FORCEPROP 1 LAST COMMENT_BODY TRUE
J 0
(-1145 3405);
DISPLAY 0.872340 (-1145 3405);
PAINT GREEN (-1145 3405);
DISPLAY INVISIBLE (-1145 3405);
FORCEPROP 2 LAST PATH I366
J 0
(-900 3550);
DISPLAY 0.680851 (-900 3550);
DISPLAY INVISIBLE (-900 3550);
FORCEADD Q_RES..1
(-2050 3500);
FORCEPROP 1 LAST LOCATION R1344
J 0
(-2250 3500);
DISPLAY 0.489362 (-2250 3500);
PAINT SKYBLUE (-2250 3500);
FORCEPROP 0 LAST $SEC 1
J 0
(-2200 3550);
DISPLAY 0.680851 (-2200 3550);
PAINT MONO (-2200 3550);
DISPLAY INVISIBLE (-2200 3550);
FORCEPROP 0 LAST CDS_SEC 1
J 0
(-2200 3550);
DISPLAY 0.680851 (-2200 3550);
DISPLAY INVISIBLE (-2200 3550);
FORCEPROP 1 LASTPIN (-2150 3500) $PN 1
J 0
(-2138 3512);
DISPLAY 0.489362 (-2138 3512);
PAINT MONO (-2138 3512);
FORCEPROP 1 LASTPIN (-1950 3500) $PN 2
J 0
(-1988 3512);
DISPLAY 0.489362 (-1988 3512);
PAINT MONO (-1988 3512);
FORCEPROP 1 LAST VALUE 0
J 2
(-1925 3500);
DISPLAY 0.489362 (-1925 3500);
PAINT SKYBLUE (-1925 3500);
FORCEPROP 2 LAST CDS_LIB pure_quanta
J 0
(-2050 3500);
DISPLAY INVISIBLE (-2050 3500);
FORCEPROP 1 LAST PATH I367
J 0
(-2100 3650);
DISPLAY 0.978723 (-2100 3650);
PAINT WHITE (-2100 3650);
DISPLAY INVISIBLE (-2100 3650);
FORCEPROP 1 LAST WATTAGE 1/16W
J 2
(-1650 3425);
DISPLAY 0.489362 (-1650 3425);
PAINT SKYBLUE (-1650 3425);
DISPLAY INVISIBLE (-1650 3425);
FORCEPROP 1 LAST MATERIAL CHIP
J 0
(-1625 3425);
DISPLAY 0.489362 (-1625 3425);
PAINT SKYBLUE (-1625 3425);
DISPLAY INVISIBLE (-1625 3425);
FORCEPROP 1 LAST TOLERANCE 5%
J 0
(-2075 3425);
DISPLAY 0.489362 (-2075 3425);
PAINT SKYBLUE (-2075 3425);
DISPLAY INVISIBLE (-2075 3425);
FORCEPROP 1 LAST PART_NUMBER CS00002JB38
J 0
(-2025 3550);
DISPLAY 0.489362 (-2025 3550);
PAINT SKYBLUE (-2025 3550);
DISPLAY INVISIBLE (-2025 3550);
FORCEPROP 1 LAST PACK_TYPE 0402LF
J 0
(-2000 3425);
DISPLAY 0.489362 (-2000 3425);
PAINT SKYBLUE (-2000 3425);
DISPLAY INVISIBLE (-2000 3425);
FORCEADD Q_RES..1
(-2050 3550);
FORCEPROP 1 LAST LOCATION R1044
J 0
(-2250 3550);
DISPLAY 0.489362 (-2250 3550);
PAINT SKYBLUE (-2250 3550);
FORCEPROP 0 LAST $SEC 1
J 0
(-2200 3600);
DISPLAY 0.680851 (-2200 3600);
PAINT MONO (-2200 3600);
DISPLAY INVISIBLE (-2200 3600);
FORCEPROP 0 LAST CDS_SEC 1
J 0
(-2200 3600);
DISPLAY 0.680851 (-2200 3600);
DISPLAY INVISIBLE (-2200 3600);
FORCEPROP 1 LASTPIN (-2150 3550) $PN 1
J 0
(-2138 3562);
DISPLAY 0.489362 (-2138 3562);
PAINT MONO (-2138 3562);
FORCEPROP 1 LASTPIN (-1950 3550) $PN 2
J 0
(-1988 3562);
DISPLAY 0.489362 (-1988 3562);
PAINT MONO (-1988 3562);
FORCEPROP 1 LAST VALUE 0
J 2
(-1925 3550);
DISPLAY 0.489362 (-1925 3550);
PAINT SKYBLUE (-1925 3550);
FORCEPROP 2 LAST CDS_LIB pure_quanta
J 0
(-2050 3550);
DISPLAY INVISIBLE (-2050 3550);
FORCEPROP 1 LAST PATH I368
J 0
(-2100 3700);
DISPLAY 0.978723 (-2100 3700);
PAINT WHITE (-2100 3700);
DISPLAY INVISIBLE (-2100 3700);
FORCEPROP 1 LAST WATTAGE 1/16W
J 2
(-1650 3475);
DISPLAY 0.489362 (-1650 3475);
PAINT SKYBLUE (-1650 3475);
DISPLAY INVISIBLE (-1650 3475);
FORCEPROP 1 LAST MATERIAL CHIP
J 0
(-1625 3475);
DISPLAY 0.489362 (-1625 3475);
PAINT SKYBLUE (-1625 3475);
DISPLAY INVISIBLE (-1625 3475);
FORCEPROP 1 LAST TOLERANCE 5%
J 0
(-2075 3475);
DISPLAY 0.489362 (-2075 3475);
PAINT SKYBLUE (-2075 3475);
DISPLAY INVISIBLE (-2075 3475);
FORCEPROP 1 LAST PART_NUMBER CS00002JB38
J 0
(-2025 3600);
DISPLAY 0.489362 (-2025 3600);
PAINT SKYBLUE (-2025 3600);
DISPLAY INVISIBLE (-2025 3600);
FORCEPROP 1 LAST PACK_TYPE 0402LF
J 0
(-2000 3475);
DISPLAY 0.489362 (-2000 3475);
PAINT SKYBLUE (-2000 3475);
DISPLAY INVISIBLE (-2000 3475);
FORCEADD OFFPAGE..2
R 2
(-7200 3000);
FORCEPROP 2 LAST $XR1 143 
J 0
(-7544 3000);
DISPLAY 0.638298 (-7544 3000);
PAINT MONO (-7544 3000);
FORCEPROP 2 LAST $XR0 34 
J 0
(-7424 3000);
DISPLAY 0.638298 (-7424 3000);
PAINT MONO (-7424 3000);
FORCEPROP 2 LAST CDS_LIB standard
J 0
(-7200 3000);
DISPLAY INVISIBLE (-7200 3000);
FORCEPROP 1 LAST OFFPAGE TRUE
J 2
(-7525 2875);
DISPLAY 0.872340 (-7525 2875);
PAINT GREEN (-7525 2875);
DISPLAY INVISIBLE (-7525 2875);
FORCEPROP 1 LAST COMMENT_BODY TRUE
J 2
(-7155 2905);
DISPLAY 0.872340 (-7155 2905);
PAINT GREEN (-7155 2905);
DISPLAY INVISIBLE (-7155 2905);
FORCEPROP 2 LAST PATH I369
J 0
(-7150 3075);
DISPLAY 0.680851 (-7150 3075);
DISPLAY INVISIBLE (-7150 3075);
FORCEADD Q_RES..1
R 2
(-6300 3000);
FORCEPROP 1 LAST LOCATION R939
J 2
(-6425 3000);
DISPLAY 0.489362 (-6425 3000);
PAINT SKYBLUE (-6425 3000);
FORCEPROP 0 LAST $SEC 1
J 0
(-6375 3050);
DISPLAY 0.680851 (-6375 3050);
PAINT MONO (-6375 3050);
DISPLAY INVISIBLE (-6375 3050);
FORCEPROP 0 LAST CDS_SEC 1
J 0
(-6375 3050);
DISPLAY 0.680851 (-6375 3050);
DISPLAY INVISIBLE (-6375 3050);
FORCEPROP 1 LASTPIN (-6200 3000) $PN 1
J 2
(-6212 3012);
DISPLAY 0.489362 (-6212 3012);
PAINT MONO (-6212 3012);
FORCEPROP 1 LASTPIN (-6400 3000) $PN 2
J 2
(-6362 3012);
DISPLAY 0.489362 (-6362 3012);
PAINT MONO (-6362 3012);
FORCEPROP 1 LAST VALUE 0
J 0
(-6200 3000);
DISPLAY 0.489362 (-6200 3000);
PAINT SKYBLUE (-6200 3000);
FORCEPROP 2 LAST CDS_LIB pure_quanta
J 0
(-6300 3000);
DISPLAY INVISIBLE (-6300 3000);
FORCEPROP 1 LAST PATH I370
J 2
(-6250 3150);
DISPLAY 0.978723 (-6250 3150);
PAINT WHITE (-6250 3150);
DISPLAY INVISIBLE (-6250 3150);
FORCEPROP 1 LAST WATTAGE 1/16W
J 0
(-6700 2925);
DISPLAY 0.489362 (-6700 2925);
PAINT SKYBLUE (-6700 2925);
DISPLAY INVISIBLE (-6700 2925);
FORCEPROP 1 LAST MATERIAL CHIP
J 2
(-6725 2925);
DISPLAY 0.489362 (-6725 2925);
PAINT SKYBLUE (-6725 2925);
DISPLAY INVISIBLE (-6725 2925);
FORCEPROP 1 LAST TOLERANCE 5%
J 2
(-6275 2925);
DISPLAY 0.489362 (-6275 2925);
PAINT SKYBLUE (-6275 2925);
DISPLAY INVISIBLE (-6275 2925);
FORCEPROP 1 LAST PART_NUMBER CS00002JB38
J 2
(-6325 3050);
DISPLAY 0.489362 (-6325 3050);
PAINT SKYBLUE (-6325 3050);
DISPLAY INVISIBLE (-6325 3050);
FORCEPROP 1 LAST PACK_TYPE 0402LF
J 2
(-6350 2925);
DISPLAY 0.489362 (-6350 2925);
PAINT SKYBLUE (-6350 2925);
DISPLAY INVISIBLE (-6350 2925);
FORCEADD Q_RES..1
R 2
(-6300 2950);
FORCEPROP 1 LAST LOCATION R940
J 2
(-6425 2950);
DISPLAY 0.489362 (-6425 2950);
PAINT SKYBLUE (-6425 2950);
FORCEPROP 0 LAST $SEC 1
J 0
(-6375 3000);
DISPLAY 0.680851 (-6375 3000);
PAINT MONO (-6375 3000);
DISPLAY INVISIBLE (-6375 3000);
FORCEPROP 0 LAST CDS_SEC 1
J 0
(-6375 3000);
DISPLAY 0.680851 (-6375 3000);
DISPLAY INVISIBLE (-6375 3000);
FORCEPROP 1 LASTPIN (-6200 2950) $PN 1
J 2
(-6212 2962);
DISPLAY 0.489362 (-6212 2962);
PAINT MONO (-6212 2962);
FORCEPROP 1 LASTPIN (-6400 2950) $PN 2
J 2
(-6362 2962);
DISPLAY 0.489362 (-6362 2962);
PAINT MONO (-6362 2962);
FORCEPROP 1 LAST VALUE 0
J 0
(-6200 2950);
DISPLAY 0.489362 (-6200 2950);
PAINT SKYBLUE (-6200 2950);
FORCEPROP 2 LAST CDS_LIB pure_quanta
J 0
(-6300 2950);
DISPLAY INVISIBLE (-6300 2950);
FORCEPROP 1 LAST PATH I371
J 2
(-6250 3100);
DISPLAY 0.978723 (-6250 3100);
PAINT WHITE (-6250 3100);
DISPLAY INVISIBLE (-6250 3100);
FORCEPROP 1 LAST WATTAGE 1/16W
J 0
(-6700 2875);
DISPLAY 0.489362 (-6700 2875);
PAINT SKYBLUE (-6700 2875);
DISPLAY INVISIBLE (-6700 2875);
FORCEPROP 1 LAST MATERIAL CHIP
J 2
(-6725 2875);
DISPLAY 0.489362 (-6725 2875);
PAINT SKYBLUE (-6725 2875);
DISPLAY INVISIBLE (-6725 2875);
FORCEPROP 1 LAST TOLERANCE 5%
J 2
(-6275 2875);
DISPLAY 0.489362 (-6275 2875);
PAINT SKYBLUE (-6275 2875);
DISPLAY INVISIBLE (-6275 2875);
FORCEPROP 1 LAST PART_NUMBER CS00002JB38
J 2
(-6325 3000);
DISPLAY 0.489362 (-6325 3000);
PAINT SKYBLUE (-6325 3000);
DISPLAY INVISIBLE (-6325 3000);
FORCEPROP 1 LAST PACK_TYPE 0402LF
J 2
(-6350 2875);
DISPLAY 0.489362 (-6350 2875);
PAINT SKYBLUE (-6350 2875);
DISPLAY INVISIBLE (-6350 2875);
FORCEADD OFFPAGE..2
R 2
(-7200 2950);
FORCEPROP 2 LAST $XR1 143 
J 0
(-7544 2950);
DISPLAY 0.638298 (-7544 2950);
PAINT MONO (-7544 2950);
FORCEPROP 2 LAST $XR0 28 
J 0
(-7424 2950);
DISPLAY 0.638298 (-7424 2950);
PAINT MONO (-7424 2950);
FORCEPROP 2 LAST CDS_LIB standard
J 0
(-7200 2950);
DISPLAY INVISIBLE (-7200 2950);
FORCEPROP 1 LAST OFFPAGE TRUE
J 2
(-7525 2825);
DISPLAY 0.872340 (-7525 2825);
PAINT GREEN (-7525 2825);
DISPLAY INVISIBLE (-7525 2825);
FORCEPROP 1 LAST COMMENT_BODY TRUE
J 2
(-7155 2855);
DISPLAY 0.872340 (-7155 2855);
PAINT GREEN (-7155 2855);
DISPLAY INVISIBLE (-7155 2855);
FORCEPROP 2 LAST PATH I372
J 0
(-7150 3025);
DISPLAY 0.680851 (-7150 3025);
DISPLAY INVISIBLE (-7150 3025);
FORCEADD Q_RES..1
(-7700 2050);
FORCEPROP 1 LAST LOCATION R938
J 0
(-7900 2050);
DISPLAY 0.489362 (-7900 2050);
PAINT SKYBLUE (-7900 2050);
FORCEPROP 0 LAST $SEC 1
J 0
(-7825 2100);
DISPLAY 0.680851 (-7825 2100);
PAINT MONO (-7825 2100);
DISPLAY INVISIBLE (-7825 2100);
FORCEPROP 0 LAST CDS_SEC 1
J 0
(-7825 2100);
DISPLAY 0.680851 (-7825 2100);
DISPLAY INVISIBLE (-7825 2100);
FORCEPROP 1 LASTPIN (-7800 2050) $PN 1
J 0
(-7788 2062);
DISPLAY 0.489362 (-7788 2062);
PAINT MONO (-7788 2062);
FORCEPROP 1 LASTPIN (-7600 2050) $PN 2
J 0
(-7638 2062);
DISPLAY 0.489362 (-7638 2062);
PAINT MONO (-7638 2062);
FORCEPROP 1 LAST VALUE 4.7K
J 0
(-7600 2050);
DISPLAY 0.489362 (-7600 2050);
PAINT SKYBLUE (-7600 2050);
FORCEPROP 2 LAST CDS_LIB pure_quanta
J 0
(-7700 2050);
DISPLAY INVISIBLE (-7700 2050);
FORCEPROP 1 LAST PATH I373
J 0
(-7750 2200);
DISPLAY 0.978723 (-7750 2200);
PAINT WHITE (-7750 2200);
DISPLAY INVISIBLE (-7750 2200);
FORCEPROP 1 LAST WATTAGE 1/16W
J 2
(-7725 1900);
DISPLAY 0.510638 (-7725 1900);
PAINT SKYBLUE (-7725 1900);
DISPLAY INVISIBLE (-7725 1900);
FORCEPROP 1 LAST MATERIAL CHIP
J 0
(-7600 2025);
DISPLAY 0.489362 (-7600 2025);
PAINT SKYBLUE (-7600 2025);
DISPLAY INVISIBLE (-7600 2025);
FORCEPROP 1 LAST TOLERANCE 5%
J 0
(-7575 2050);
DISPLAY 0.510638 (-7575 2050);
PAINT SKYBLUE (-7575 2050);
DISPLAY INVISIBLE (-7575 2050);
FORCEPROP 1 LAST PART_NUMBER TMP_QCS24702JB38
J 0
(-7750 2150);
DISPLAY 0.510638 (-7750 2150);
PAINT SKYBLUE (-7750 2150);
DISPLAY INVISIBLE (-7750 2150);
FORCEPROP 1 LAST PACK_TYPE 0402LF
J 0
(-7450 1900);
DISPLAY 0.510638 (-7450 1900);
PAINT SKYBLUE (-7450 1900);
DISPLAY INVISIBLE (-7450 1900);
FORCEADD OFFPAGE..2
R 2
(-8675 2050);
FORCEPROP 2 LAST $XR1 143 
J 0
(-9019 2050);
DISPLAY 0.638298 (-9019 2050);
PAINT MONO (-9019 2050);
FORCEPROP 2 LAST $XR0 28 
J 0
(-8899 2050);
DISPLAY 0.638298 (-8899 2050);
PAINT MONO (-8899 2050);
FORCEPROP 2 LAST CDS_LIB standard
J 0
(-8675 2050);
DISPLAY INVISIBLE (-8675 2050);
FORCEPROP 1 LAST OFFPAGE TRUE
J 2
(-9000 1925);
DISPLAY 0.872340 (-9000 1925);
PAINT GREEN (-9000 1925);
DISPLAY INVISIBLE (-9000 1925);
FORCEPROP 1 LAST COMMENT_BODY TRUE
J 2
(-8630 1955);
DISPLAY 0.872340 (-8630 1955);
PAINT GREEN (-8630 1955);
DISPLAY INVISIBLE (-8630 1955);
FORCEPROP 2 LAST PATH I374
J 0
(-8625 2125);
DISPLAY 0.680851 (-8625 2125);
DISPLAY INVISIBLE (-8625 2125);
FORCEADD OFFPAGE..4
R 2
(-7200 2900);
FORCEPROP 2 LAST $XR2 142 
J 0
(-7661 2900);
DISPLAY 0.638298 (-7661 2900);
PAINT MONO (-7661 2900);
FORCEPROP 2 LAST $XR1 144 
J 0
(-7541 2900);
DISPLAY 0.638298 (-7541 2900);
PAINT MONO (-7541 2900);
FORCEPROP 2 LAST $XR0 80 
J 0
(-7421 2900);
DISPLAY 0.638298 (-7421 2900);
PAINT MONO (-7421 2900);
FORCEPROP 2 LAST CDS_LIB standard
J 0
(-7200 2900);
DISPLAY INVISIBLE (-7200 2900);
FORCEPROP 1 LAST OFFPAGE TRUE
J 2
(-7525 2775);
DISPLAY 0.872340 (-7525 2775);
PAINT GREEN (-7525 2775);
DISPLAY INVISIBLE (-7525 2775);
FORCEPROP 1 LAST COMMENT_BODY TRUE
J 2
(-7175 2800);
DISPLAY 0.872340 (-7175 2800);
PAINT GREEN (-7175 2800);
DISPLAY INVISIBLE (-7175 2800);
FORCEPROP 2 LAST PATH I376
J 0
(-7150 2975);
DISPLAY 0.680851 (-7150 2975);
DISPLAY INVISIBLE (-7150 2975);
FORCEADD OFFPAGE..4
R 2
(-7225 3400);
FORCEPROP 2 LAST $XR0 144 
J 0
(-7477 3400);
DISPLAY 0.638298 (-7477 3400);
PAINT MONO (-7477 3400);
FORCEPROP 2 LAST CDS_LIB standard
J 0
(-7225 3400);
DISPLAY INVISIBLE (-7225 3400);
FORCEPROP 1 LAST OFFPAGE TRUE
J 2
(-7550 3275);
DISPLAY 0.872340 (-7550 3275);
PAINT GREEN (-7550 3275);
DISPLAY INVISIBLE (-7550 3275);
FORCEPROP 1 LAST COMMENT_BODY TRUE
J 2
(-7200 3300);
DISPLAY 0.872340 (-7200 3300);
PAINT GREEN (-7200 3300);
DISPLAY INVISIBLE (-7200 3300);
FORCEPROP 2 LAST PATH I377
J 0
(-7175 3475);
DISPLAY 0.680851 (-7175 3475);
DISPLAY INVISIBLE (-7175 3475);
FORCEADD Q_RES..1
R 2
(-6300 3400);
FORCEPROP 1 LAST LOCATION R1205
J 2
(-6400 3400);
DISPLAY 0.489362 (-6400 3400);
PAINT SKYBLUE (-6400 3400);
FORCEPROP 0 LAST $SEC 1
J 0
(-6400 3450);
DISPLAY 0.680851 (-6400 3450);
PAINT MONO (-6400 3450);
DISPLAY INVISIBLE (-6400 3450);
FORCEPROP 0 LAST CDS_SEC 1
J 0
(-6400 3450);
DISPLAY 0.680851 (-6400 3450);
DISPLAY INVISIBLE (-6400 3450);
FORCEPROP 1 LASTPIN (-6200 3400) $PN 1
J 2
(-6212 3412);
DISPLAY 0.489362 (-6212 3412);
PAINT MONO (-6212 3412);
FORCEPROP 1 LASTPIN (-6400 3400) $PN 2
J 2
(-6362 3412);
DISPLAY 0.489362 (-6362 3412);
PAINT MONO (-6362 3412);
FORCEPROP 1 LAST VALUE 0
J 0
(-6200 3400);
DISPLAY 0.489362 (-6200 3400);
PAINT SKYBLUE (-6200 3400);
FORCEPROP 2 LAST CDS_LIB pure_quanta
J 0
(-6300 3400);
DISPLAY INVISIBLE (-6300 3400);
FORCEPROP 1 LAST PATH I378
J 2
(-6250 3550);
DISPLAY 0.978723 (-6250 3550);
PAINT WHITE (-6250 3550);
DISPLAY INVISIBLE (-6250 3550);
FORCEPROP 1 LAST WATTAGE 1/16W
J 0
(-6700 3325);
DISPLAY 0.489362 (-6700 3325);
PAINT SKYBLUE (-6700 3325);
DISPLAY INVISIBLE (-6700 3325);
FORCEPROP 1 LAST MATERIAL CHIP
J 2
(-6725 3325);
DISPLAY 0.489362 (-6725 3325);
PAINT SKYBLUE (-6725 3325);
DISPLAY INVISIBLE (-6725 3325);
FORCEPROP 1 LAST TOLERANCE 5%
J 2
(-6275 3325);
DISPLAY 0.489362 (-6275 3325);
PAINT SKYBLUE (-6275 3325);
DISPLAY INVISIBLE (-6275 3325);
FORCEPROP 1 LAST PART_NUMBER CS00002JB38
J 2
(-6325 3450);
DISPLAY 0.489362 (-6325 3450);
PAINT SKYBLUE (-6325 3450);
DISPLAY INVISIBLE (-6325 3450);
FORCEPROP 1 LAST PACK_TYPE 0402LF
J 2
(-6350 3325);
DISPLAY 0.489362 (-6350 3325);
PAINT SKYBLUE (-6350 3325);
DISPLAY INVISIBLE (-6350 3325);
FORCEADD OFFPAGE..1
R 2
(-525 5500);
FORCEPROP 2 LAST $XR1 55 
J 0
(-219 5500);
DISPLAY 0.638298 (-219 5500);
PAINT MONO (-219 5500);
FORCEPROP 2 LAST $XR0 132 
J 0
(-339 5500);
DISPLAY 0.638298 (-339 5500);
PAINT MONO (-339 5500);
FORCEPROP 1 LAST COMMENT_BODY TRUE
J 2
(-650 5400);
DISPLAY 0.872340 (-650 5400);
PAINT GREEN (-650 5400);
DISPLAY INVISIBLE (-650 5400);
FORCEPROP 1 LAST OFFPAGE TRUE
J 2
(-850 5375);
DISPLAY 0.872340 (-850 5375);
PAINT GREEN (-850 5375);
DISPLAY INVISIBLE (-850 5375);
FORCEPROP 2 LAST CDS_LIB standard
J 2
(-525 5500);
DISPLAY INVISIBLE (-525 5500);
FORCEPROP 2 LAST PATH I379
J 0
(-200 5550);
DISPLAY 0.680851 (-200 5550);
DISPLAY INVISIBLE (-200 5550);
FORCEADD Q_RES..2
(-8525 6125);
FORCEPROP 1 LAST LOCATION R424
J 0
(-8475 6250);
DISPLAY 0.489362 (-8475 6250);
PAINT SKYBLUE (-8475 6250);
FORCEPROP 0 LAST $SEC 1
J 0
(-8475 6275);
DISPLAY 0.680851 (-8475 6275);
PAINT MONO (-8475 6275);
DISPLAY INVISIBLE (-8475 6275);
FORCEPROP 0 LAST CDS_SEC 1
J 0
(-8475 6275);
DISPLAY 0.680851 (-8475 6275);
DISPLAY INVISIBLE (-8475 6275);
FORCEPROP 1 LASTPIN (-8525 6225) $PN 1
J 0
(-8520 6187);
DISPLAY 0.489362 (-8520 6187);
PAINT MONO (-8520 6187);
FORCEPROP 1 LASTPIN (-8525 6025) $PN 2
J 0
(-8520 6035);
DISPLAY 0.489362 (-8520 6035);
PAINT MONO (-8520 6035);
FORCEPROP 1 LAST PART_NUMBER CS22202JB07
J 0
(-8475 6150);
DISPLAY 0.489362 (-8475 6150);
PAINT SKYBLUE (-8475 6150);
FORCEPROP 1 LAST VALUE 2.2K
J 0
(-8475 6200);
DISPLAY 0.489362 (-8475 6200);
PAINT SKYBLUE (-8475 6200);
FORCEPROP 2 LAST CDS_LIB pure_quanta
J 0
(-8525 6125);
DISPLAY INVISIBLE (-8525 6125);
FORCEPROP 1 LAST PATH I380
J 0
(-8475 6300);
DISPLAY 0.978723 (-8475 6300);
PAINT WHITE (-8475 6300);
DISPLAY INVISIBLE (-8475 6300);
FORCEPROP 1 LAST WATTAGE 1/16W
J 0
(-8485 6100);
DISPLAY 0.510638 (-8485 6100);
PAINT SKYBLUE (-8485 6100);
DISPLAY INVISIBLE (-8485 6100);
FORCEPROP 1 LAST MATERIAL CHIP
J 0
(-8485 6050);
DISPLAY 0.510638 (-8485 6050);
PAINT SKYBLUE (-8485 6050);
DISPLAY INVISIBLE (-8485 6050);
FORCEPROP 1 LAST TOLERANCE 5%
J 0
(-8480 6150);
DISPLAY 0.510638 (-8480 6150);
PAINT SKYBLUE (-8480 6150);
DISPLAY INVISIBLE (-8480 6150);
FORCEPROP 1 LAST PACK_TYPE 0402LF
J 0
(-8475 6100);
DISPLAY 0.489362 (-8475 6100);
PAINT SKYBLUE (-8475 6100);
DISPLAY INVISIBLE (-8475 6100);
FORCEADD Q_RES..1
(-7700 1250);
FORCEPROP 1 LAST LOCATION R207
J 0
(-7900 1250);
DISPLAY 0.489362 (-7900 1250);
PAINT SKYBLUE (-7900 1250);
FORCEPROP 0 LAST $SEC 1
J 0
(-7600 1275);
DISPLAY 0.680851 (-7600 1275);
PAINT MONO (-7600 1275);
DISPLAY INVISIBLE (-7600 1275);
FORCEPROP 0 LAST CDS_SEC 1
J 0
(-7600 1275);
DISPLAY 0.680851 (-7600 1275);
DISPLAY INVISIBLE (-7600 1275);
FORCEPROP 1 LASTPIN (-7800 1250) $PN 1
J 0
(-7788 1262);
DISPLAY 0.489362 (-7788 1262);
PAINT MONO (-7788 1262);
FORCEPROP 1 LASTPIN (-7600 1250) $PN 2
J 0
(-7638 1262);
DISPLAY 0.489362 (-7638 1262);
PAINT MONO (-7638 1262);
FORCEPROP 1 LAST VALUE 2.2K
J 0
(-7600 1250);
DISPLAY 0.489362 (-7600 1250);
PAINT SKYBLUE (-7600 1250);
FORCEPROP 2 LAST CDS_LIB pure_quanta
J 0
(-7700 1250);
DISPLAY INVISIBLE (-7700 1250);
FORCEPROP 1 LAST PATH I381
J 0
(-7750 1400);
DISPLAY 0.978723 (-7750 1400);
PAINT WHITE (-7750 1400);
DISPLAY INVISIBLE (-7750 1400);
FORCEPROP 1 LAST WATTAGE 1/16W
J 2
(-7725 1100);
DISPLAY 0.978723 (-7725 1100);
PAINT SKYBLUE (-7725 1100);
DISPLAY INVISIBLE (-7725 1100);
FORCEPROP 1 LAST MATERIAL CHIP
J 0
(-7700 1100);
DISPLAY 0.978723 (-7700 1100);
PAINT SKYBLUE (-7700 1100);
DISPLAY INVISIBLE (-7700 1100);
FORCEPROP 1 LAST TOLERANCE 5%
J 0
(-7700 1150);
DISPLAY 0.978723 (-7700 1150);
PAINT SKYBLUE (-7700 1150);
DISPLAY INVISIBLE (-7700 1150);
FORCEPROP 1 LAST PART_NUMBER CS22202JB07
J 0
(-7750 1350);
DISPLAY 0.978723 (-7750 1350);
PAINT SKYBLUE (-7750 1350);
DISPLAY INVISIBLE (-7750 1350);
FORCEPROP 1 LAST PACK_TYPE 0402LF
J 0
(-7450 1100);
DISPLAY 0.978723 (-7450 1100);
PAINT SKYBLUE (-7450 1100);
DISPLAY INVISIBLE (-7450 1100);
FORCEADD Q_RES..1
(-7700 1750);
FORCEPROP 1 LAST LOCATION R443
J 0
(-7900 1750);
DISPLAY 0.489362 (-7900 1750);
PAINT SKYBLUE (-7900 1750);
FORCEPROP 0 LAST $SEC 1
J 0
(-7600 1775);
DISPLAY 0.680851 (-7600 1775);
PAINT MONO (-7600 1775);
DISPLAY INVISIBLE (-7600 1775);
FORCEPROP 0 LAST CDS_SEC 1
J 0
(-7600 1775);
DISPLAY 0.680851 (-7600 1775);
DISPLAY INVISIBLE (-7600 1775);
FORCEPROP 1 LASTPIN (-7800 1750) $PN 1
J 0
(-7788 1762);
DISPLAY 0.489362 (-7788 1762);
PAINT MONO (-7788 1762);
FORCEPROP 1 LASTPIN (-7600 1750) $PN 2
J 0
(-7638 1762);
DISPLAY 0.489362 (-7638 1762);
PAINT MONO (-7638 1762);
FORCEPROP 1 LAST VALUE 1K
J 0
(-7600 1750);
DISPLAY 0.489362 (-7600 1750);
PAINT SKYBLUE (-7600 1750);
FORCEPROP 2 LAST CDS_LIB pure_quanta
J 0
(-7700 1750);
DISPLAY INVISIBLE (-7700 1750);
FORCEPROP 1 LAST PATH I383
J 0
(-7750 1900);
DISPLAY 0.978723 (-7750 1900);
PAINT WHITE (-7750 1900);
DISPLAY INVISIBLE (-7750 1900);
FORCEPROP 1 LAST WATTAGE 1/16W
J 2
(-7725 1600);
DISPLAY 0.978723 (-7725 1600);
PAINT SKYBLUE (-7725 1600);
DISPLAY INVISIBLE (-7725 1600);
FORCEPROP 1 LAST MATERIAL CHIP
J 0
(-7700 1600);
DISPLAY 0.978723 (-7700 1600);
PAINT SKYBLUE (-7700 1600);
DISPLAY INVISIBLE (-7700 1600);
FORCEPROP 1 LAST TOLERANCE 5%
J 0
(-7700 1650);
DISPLAY 0.978723 (-7700 1650);
PAINT SKYBLUE (-7700 1650);
DISPLAY INVISIBLE (-7700 1650);
FORCEPROP 1 LAST PART_NUMBER TMP_QCS21002JB34
J 0
(-7750 1850);
DISPLAY 0.978723 (-7750 1850);
PAINT SKYBLUE (-7750 1850);
DISPLAY INVISIBLE (-7750 1850);
FORCEPROP 1 LAST PACK_TYPE 0402LF
J 0
(-7450 1600);
DISPLAY 0.978723 (-7450 1600);
PAINT SKYBLUE (-7450 1600);
DISPLAY INVISIBLE (-7450 1600);
FORCEADD Q_RES..1
(-7700 1800);
FORCEPROP 1 LAST LOCATION R442
J 0
(-7900 1800);
DISPLAY 0.489362 (-7900 1800);
PAINT SKYBLUE (-7900 1800);
FORCEPROP 0 LAST $SEC 1
J 0
(-7600 1825);
DISPLAY 0.680851 (-7600 1825);
PAINT MONO (-7600 1825);
DISPLAY INVISIBLE (-7600 1825);
FORCEPROP 0 LAST CDS_SEC 1
J 0
(-7600 1825);
DISPLAY 0.680851 (-7600 1825);
DISPLAY INVISIBLE (-7600 1825);
FORCEPROP 1 LASTPIN (-7800 1800) $PN 1
J 0
(-7788 1812);
DISPLAY 0.489362 (-7788 1812);
PAINT MONO (-7788 1812);
FORCEPROP 1 LASTPIN (-7600 1800) $PN 2
J 0
(-7638 1812);
DISPLAY 0.489362 (-7638 1812);
PAINT MONO (-7638 1812);
FORCEPROP 1 LAST VALUE 1K
J 0
(-7600 1800);
DISPLAY 0.489362 (-7600 1800);
PAINT SKYBLUE (-7600 1800);
FORCEPROP 2 LAST CDS_LIB pure_quanta
J 0
(-7700 1800);
DISPLAY INVISIBLE (-7700 1800);
FORCEPROP 1 LAST PATH I384
J 0
(-7750 1950);
DISPLAY 0.978723 (-7750 1950);
PAINT WHITE (-7750 1950);
DISPLAY INVISIBLE (-7750 1950);
FORCEPROP 1 LAST WATTAGE 1/16W
J 2
(-7725 1650);
DISPLAY 0.978723 (-7725 1650);
PAINT SKYBLUE (-7725 1650);
DISPLAY INVISIBLE (-7725 1650);
FORCEPROP 1 LAST MATERIAL CHIP
J 0
(-7700 1650);
DISPLAY 0.978723 (-7700 1650);
PAINT SKYBLUE (-7700 1650);
DISPLAY INVISIBLE (-7700 1650);
FORCEPROP 1 LAST TOLERANCE 5%
J 0
(-7700 1700);
DISPLAY 0.978723 (-7700 1700);
PAINT SKYBLUE (-7700 1700);
DISPLAY INVISIBLE (-7700 1700);
FORCEPROP 1 LAST PART_NUMBER TMP_QCS21002JB34
J 0
(-7750 1900);
DISPLAY 0.978723 (-7750 1900);
PAINT SKYBLUE (-7750 1900);
DISPLAY INVISIBLE (-7750 1900);
FORCEPROP 1 LAST PACK_TYPE 0402LF
J 0
(-7450 1650);
DISPLAY 0.978723 (-7450 1650);
PAINT SKYBLUE (-7450 1650);
DISPLAY INVISIBLE (-7450 1650);
FORCEADD Q_RES..1
(-7700 1850);
FORCEPROP 1 LAST LOCATION R441
J 0
(-7900 1850);
DISPLAY 0.489362 (-7900 1850);
PAINT SKYBLUE (-7900 1850);
FORCEPROP 0 LAST $SEC 1
J 0
(-7600 1875);
DISPLAY 0.680851 (-7600 1875);
PAINT MONO (-7600 1875);
DISPLAY INVISIBLE (-7600 1875);
FORCEPROP 0 LAST CDS_SEC 1
J 0
(-7600 1875);
DISPLAY 0.680851 (-7600 1875);
DISPLAY INVISIBLE (-7600 1875);
FORCEPROP 1 LASTPIN (-7800 1850) $PN 1
J 0
(-7788 1862);
DISPLAY 0.489362 (-7788 1862);
PAINT MONO (-7788 1862);
FORCEPROP 1 LASTPIN (-7600 1850) $PN 2
J 0
(-7638 1862);
DISPLAY 0.489362 (-7638 1862);
PAINT MONO (-7638 1862);
FORCEPROP 1 LAST VALUE 2.2K
J 0
(-7600 1850);
DISPLAY 0.489362 (-7600 1850);
PAINT SKYBLUE (-7600 1850);
FORCEPROP 2 LAST CDS_LIB pure_quanta
J 0
(-7700 1850);
DISPLAY INVISIBLE (-7700 1850);
FORCEPROP 1 LAST PATH I385
J 0
(-7750 2000);
DISPLAY 0.978723 (-7750 2000);
PAINT WHITE (-7750 2000);
DISPLAY INVISIBLE (-7750 2000);
FORCEPROP 1 LAST WATTAGE 1/16W
J 2
(-7725 1700);
DISPLAY 0.978723 (-7725 1700);
PAINT SKYBLUE (-7725 1700);
DISPLAY INVISIBLE (-7725 1700);
FORCEPROP 1 LAST MATERIAL CHIP
J 0
(-7700 1700);
DISPLAY 0.978723 (-7700 1700);
PAINT SKYBLUE (-7700 1700);
DISPLAY INVISIBLE (-7700 1700);
FORCEPROP 1 LAST TOLERANCE 5%
J 0
(-7700 1750);
DISPLAY 0.978723 (-7700 1750);
PAINT SKYBLUE (-7700 1750);
DISPLAY INVISIBLE (-7700 1750);
FORCEPROP 1 LAST PART_NUMBER CS22202JB07
J 0
(-7750 1950);
DISPLAY 0.978723 (-7750 1950);
PAINT SKYBLUE (-7750 1950);
DISPLAY INVISIBLE (-7750 1950);
FORCEPROP 1 LAST PACK_TYPE 0402LF
J 0
(-7450 1700);
DISPLAY 0.978723 (-7450 1700);
PAINT SKYBLUE (-7450 1700);
DISPLAY INVISIBLE (-7450 1700);
FORCEADD Q_RES..1
(-6425 5700);
FORCEPROP 1 LAST LOCATION R249
J 0
(-6300 5700);
DISPLAY 0.489362 (-6300 5700);
PAINT SKYBLUE (-6300 5700);
FORCEPROP 0 LAST $SEC 1
J 2
(-6300 5750);
DISPLAY 0.680851 (-6300 5750);
PAINT MONO (-6300 5750);
DISPLAY INVISIBLE (-6300 5750);
FORCEPROP 0 LAST CDS_SEC 1
J 2
(-6300 5750);
DISPLAY 1.021277 (-6300 5750);
DISPLAY INVISIBLE (-6300 5750);
FORCEPROP 1 LASTPIN (-6525 5700) $PN 1
J 0
(-6513 5712);
DISPLAY 0.489362 (-6513 5712);
PAINT MONO (-6513 5712);
FORCEPROP 1 LASTPIN (-6325 5700) $PN 2
J 0
(-6363 5712);
DISPLAY 0.489362 (-6363 5712);
PAINT MONO (-6363 5712);
FORCEPROP 1 LAST VALUE 33
J 2
(-6550 5700);
DISPLAY 0.489362 (-6550 5700);
PAINT SKYBLUE (-6550 5700);
FORCEPROP 2 LAST CDS_LIB pure_quanta
J 2
(-6425 5700);
DISPLAY INVISIBLE (-6425 5700);
FORCEPROP 2 LAST BOM_COST MEM
J 2
(-6400 5850);
DISPLAY 0.744681 (-6400 5850);
PAINT WHITE (-6400 5850);
DISPLAY INVISIBLE (-6400 5850);
FORCEPROP 1 LAST PATH I386
J 0
(-6475 5850);
DISPLAY 0.978723 (-6475 5850);
PAINT WHITE (-6475 5850);
DISPLAY INVISIBLE (-6475 5850);
FORCEPROP 1 LAST WATTAGE 1/16W
J 2
(-6500 5625);
DISPLAY 0.489362 (-6500 5625);
PAINT SKYBLUE (-6500 5625);
DISPLAY INVISIBLE (-6500 5625);
FORCEPROP 1 LAST MATERIAL CHIP
J 2
(-6250 5675);
DISPLAY 0.489362 (-6250 5675);
PAINT SKYBLUE (-6250 5675);
DISPLAY INVISIBLE (-6250 5675);
FORCEPROP 1 LAST TOLERANCE 5%
J 0
(-6550 5675);
DISPLAY 0.489362 (-6550 5675);
PAINT SKYBLUE (-6550 5675);
DISPLAY INVISIBLE (-6550 5675);
FORCEPROP 1 LAST PART_NUMBER CS03302JB29
J 2
(-6325 5750);
DISPLAY 0.489362 (-6325 5750);
PAINT SKYBLUE (-6325 5750);
DISPLAY INVISIBLE (-6325 5750);
FORCEPROP 1 LAST PACK_TYPE 0402LF
J 2
(-6250 5625);
DISPLAY 0.489362 (-6250 5625);
PAINT SKYBLUE (-6250 5625);
DISPLAY INVISIBLE (-6250 5625);
FORCEPROP 2 LAST ROOM RST_CPU0_PLD_TO_DIMM
J 2
(-6400 5800);
DISPLAY 0.744681 (-6400 5800);
PAINT RED (-6400 5800);
DISPLAY INVISIBLE (-6400 5800);
FORCEADD Q_RES..1
(-6425 5750);
FORCEPROP 1 LAST LOCATION R248
J 0
(-6300 5750);
DISPLAY 0.489362 (-6300 5750);
PAINT SKYBLUE (-6300 5750);
FORCEPROP 0 LAST $SEC 1
J 2
(-6300 5800);
DISPLAY 0.680851 (-6300 5800);
PAINT MONO (-6300 5800);
DISPLAY INVISIBLE (-6300 5800);
FORCEPROP 0 LAST CDS_SEC 1
J 2
(-6300 5800);
DISPLAY 1.021277 (-6300 5800);
DISPLAY INVISIBLE (-6300 5800);
FORCEPROP 1 LASTPIN (-6525 5750) $PN 1
J 0
(-6513 5762);
DISPLAY 0.489362 (-6513 5762);
PAINT MONO (-6513 5762);
FORCEPROP 1 LASTPIN (-6325 5750) $PN 2
J 0
(-6363 5762);
DISPLAY 0.489362 (-6363 5762);
PAINT MONO (-6363 5762);
FORCEPROP 1 LAST VALUE 33
J 2
(-6550 5750);
DISPLAY 0.489362 (-6550 5750);
PAINT SKYBLUE (-6550 5750);
FORCEPROP 2 LAST CDS_LIB pure_quanta
J 2
(-6425 5750);
DISPLAY INVISIBLE (-6425 5750);
FORCEPROP 2 LAST BOM_COST MEM
J 2
(-6400 5900);
DISPLAY 0.744681 (-6400 5900);
PAINT WHITE (-6400 5900);
DISPLAY INVISIBLE (-6400 5900);
FORCEPROP 1 LAST PATH I387
J 0
(-6475 5900);
DISPLAY 0.978723 (-6475 5900);
PAINT WHITE (-6475 5900);
DISPLAY INVISIBLE (-6475 5900);
FORCEPROP 1 LAST WATTAGE 1/16W
J 2
(-6500 5675);
DISPLAY 0.489362 (-6500 5675);
PAINT SKYBLUE (-6500 5675);
DISPLAY INVISIBLE (-6500 5675);
FORCEPROP 1 LAST MATERIAL CHIP
J 2
(-6250 5725);
DISPLAY 0.489362 (-6250 5725);
PAINT SKYBLUE (-6250 5725);
DISPLAY INVISIBLE (-6250 5725);
FORCEPROP 1 LAST TOLERANCE 5%
J 0
(-6550 5725);
DISPLAY 0.489362 (-6550 5725);
PAINT SKYBLUE (-6550 5725);
DISPLAY INVISIBLE (-6550 5725);
FORCEPROP 1 LAST PART_NUMBER CS03302JB29
J 2
(-6325 5800);
DISPLAY 0.489362 (-6325 5800);
PAINT SKYBLUE (-6325 5800);
DISPLAY INVISIBLE (-6325 5800);
FORCEPROP 1 LAST PACK_TYPE 0402LF
J 2
(-6250 5675);
DISPLAY 0.489362 (-6250 5675);
PAINT SKYBLUE (-6250 5675);
DISPLAY INVISIBLE (-6250 5675);
FORCEPROP 2 LAST ROOM RST_CPU0_PLD_TO_DIMM
J 2
(-6400 5850);
DISPLAY 0.744681 (-6400 5850);
PAINT RED (-6400 5850);
DISPLAY INVISIBLE (-6400 5850);
FORCEADD OFFPAGE..2
R 2
(-7150 5750);
FORCEPROP 2 LAST $XR0 80 
J 0
(-7404 5750);
DISPLAY 0.638298 (-7404 5750);
PAINT MONO (-7404 5750);
FORCEPROP 2 LAST CDS_LIB standard
J 2
(-7150 5750);
DISPLAY INVISIBLE (-7150 5750);
FORCEPROP 1 LAST OFFPAGE TRUE
J 2
(-7475 5625);
DISPLAY 0.872340 (-7475 5625);
PAINT GREEN (-7475 5625);
DISPLAY INVISIBLE (-7475 5625);
FORCEPROP 1 LAST COMMENT_BODY TRUE
J 2
(-7105 5655);
DISPLAY 0.872340 (-7105 5655);
PAINT GREEN (-7105 5655);
DISPLAY INVISIBLE (-7105 5655);
FORCEPROP 2 LAST PATH I388
J 0
(-7350 5800);
DISPLAY 0.680851 (-7350 5800);
DISPLAY INVISIBLE (-7350 5800);
FORCEADD OFFPAGE..2
R 2
(-7150 5700);
FORCEPROP 2 LAST $XR0 80 
J 0
(-7404 5700);
DISPLAY 0.638298 (-7404 5700);
PAINT MONO (-7404 5700);
FORCEPROP 2 LAST CDS_LIB standard
J 2
(-7150 5700);
DISPLAY INVISIBLE (-7150 5700);
FORCEPROP 1 LAST OFFPAGE TRUE
J 2
(-7475 5575);
DISPLAY 0.872340 (-7475 5575);
PAINT GREEN (-7475 5575);
DISPLAY INVISIBLE (-7475 5575);
FORCEPROP 1 LAST COMMENT_BODY TRUE
J 2
(-7105 5605);
DISPLAY 0.872340 (-7105 5605);
PAINT GREEN (-7105 5605);
DISPLAY INVISIBLE (-7105 5605);
FORCEPROP 2 LAST PATH I389
J 0
(-7350 5750);
DISPLAY 0.680851 (-7350 5750);
DISPLAY INVISIBLE (-7350 5750);
FORCEADD UNIVERSAL_GND..1
(-3825 800);
FORCEPROP 3 LASTPIN (-3825 850) SIG_NAME GND\g
J 0
(-3815 860);
DISPLAY 0.659574 (-3815 860);
PAINT MONO (-3815 860);
DISPLAY INVISIBLE (-3815 860);
FORCEPROP 2 LAST CDS_LIB pure_quanta_power
J 0
(-3825 800);
DISPLAY INVISIBLE (-3825 800);
FORCEPROP 1 LAST PATH I4
J 0
(-3750 800);
DISPLAY 0.872340 (-3750 800);
PAINT AQUA (-3750 800);
DISPLAY INVISIBLE (-3750 800);
FORCEPROP 1 LAST HDL_POWER GND
J 1
(-3800 725);
DISPLAY 0.872340 (-3800 725);
PAINT GREEN (-3800 725);
DISPLAY INVISIBLE (-3800 725);
FORCEADD Q_CAP..1
(-3825 1125);
FORCEPROP 1 LAST LOCATION C215
J 0
(-3775 1225);
DISPLAY 0.489362 (-3775 1225);
PAINT SKYBLUE (-3775 1225);
FORCEPROP 0 LAST $SEC 1
J 0
(-3775 1275);
DISPLAY 0.680851 (-3775 1275);
PAINT MONO (-3775 1275);
DISPLAY INVISIBLE (-3775 1275);
FORCEPROP 0 LAST CDS_SEC 1
J 0
(-3775 1275);
DISPLAY 1.021277 (-3775 1275);
DISPLAY INVISIBLE (-3775 1275);
FORCEPROP 1 LASTPIN (-3825 1225) $PN 1
J 0
(-3815 1205);
DISPLAY 0.489362 (-3815 1205);
PAINT MONO (-3815 1205);
FORCEPROP 1 LASTPIN (-3825 1025) $PN 2
J 0
(-3815 1005);
DISPLAY 0.489362 (-3815 1005);
PAINT MONO (-3815 1005);
FORCEPROP 1 LAST PART_NUMBER TMP_QCH0106F0B00
J 0
(-3775 975);
DISPLAY 0.489362 (-3775 975);
PAINT SKYBLUE (-3775 975);
FORCEPROP 1 LAST TOLERANCE 1%
J 0
(-3775 1075);
DISPLAY 0.489362 (-3775 1075);
PAINT SKYBLUE (-3775 1075);
FORCEPROP 1 LAST MATERIAL NPO
J 0
(-3775 1025);
DISPLAY 0.489362 (-3775 1025);
PAINT SKYBLUE (-3775 1025);
FORCEPROP 1 LAST PACK_TYPE 0402
J 0
(-3775 925);
DISPLAY 0.489362 (-3775 925);
PAINT SKYBLUE (-3775 925);
FORCEPROP 1 LAST VOLTAGE 50V
J 0
(-3775 1125);
DISPLAY 0.489362 (-3775 1125);
PAINT SKYBLUE (-3775 1125);
FORCEPROP 1 LAST VALUE 10PF
J 0
(-3775 1175);
DISPLAY 0.489362 (-3775 1175);
PAINT SKYBLUE (-3775 1175);
FORCEPROP 1 LAST PATH I5
J 0
(-3775 1275);
DISPLAY 0.978723 (-3775 1275);
PAINT WHITE (-3775 1275);
DISPLAY INVISIBLE (-3775 1275);
FORCEPROP 2 LAST CDS_LIB pure_quanta
J 0
(-3825 1125);
DISPLAY INVISIBLE (-3825 1125);
FORCEADD Q_RES..1
R 2
(-6775 3950);
FORCEPROP 1 LAST LOCATION R431
J 0
(-6525 3950);
DISPLAY 0.489362 (-6525 3950);
PAINT SKYBLUE (-6525 3950);
FORCEPROP 0 LAST $SEC 1
J 2
(-6500 4000);
DISPLAY 0.680851 (-6500 4000);
PAINT MONO (-6500 4000);
DISPLAY INVISIBLE (-6500 4000);
FORCEPROP 0 LAST CDS_SEC 1
J 2
(-6500 4000);
DISPLAY 1.021277 (-6500 4000);
DISPLAY INVISIBLE (-6500 4000);
FORCEPROP 1 LASTPIN (-6675 3950) $PN 1
J 2
(-6687 3962);
DISPLAY 0.489362 (-6687 3962);
PAINT MONO (-6687 3962);
FORCEPROP 1 LASTPIN (-6875 3950) $PN 2
J 2
(-6837 3962);
DISPLAY 0.489362 (-6837 3962);
PAINT MONO (-6837 3962);
FORCEPROP 1 LAST VALUE 0
J 0
(-6675 3950);
DISPLAY 0.489362 (-6675 3950);
PAINT SKYBLUE (-6675 3950);
FORCEPROP 2 LAST CDS_LIB pure_quanta
J 2
(-6775 3950);
DISPLAY INVISIBLE (-6775 3950);
FORCEPROP 1 LAST PATH I54
J 2
(-6725 4100);
DISPLAY 0.978723 (-6725 4100);
PAINT WHITE (-6725 4100);
DISPLAY INVISIBLE (-6725 4100);
FORCEPROP 1 LAST WATTAGE 1/16W
J 0
(-7175 3875);
DISPLAY 0.489362 (-7175 3875);
PAINT SKYBLUE (-7175 3875);
DISPLAY INVISIBLE (-7175 3875);
FORCEPROP 1 LAST MATERIAL CHIP
J 2
(-7200 3875);
DISPLAY 0.489362 (-7200 3875);
PAINT SKYBLUE (-7200 3875);
DISPLAY INVISIBLE (-7200 3875);
FORCEPROP 1 LAST TOLERANCE 5%
J 2
(-6750 3875);
DISPLAY 0.489362 (-6750 3875);
PAINT SKYBLUE (-6750 3875);
DISPLAY INVISIBLE (-6750 3875);
FORCEPROP 1 LAST PART_NUMBER CS00002JB38
J 2
(-6800 4000);
DISPLAY 0.489362 (-6800 4000);
PAINT SKYBLUE (-6800 4000);
DISPLAY INVISIBLE (-6800 4000);
FORCEPROP 1 LAST PACK_TYPE 0402LF
J 2
(-6825 3875);
DISPLAY 0.489362 (-6825 3875);
PAINT SKYBLUE (-6825 3875);
DISPLAY INVISIBLE (-6825 3875);
FORCEADD OFFPAGE..2
R 2
(-7825 4000);
FORCEPROP 2 LAST $XR0 34 
J 0
(-8079 4000);
DISPLAY 0.638298 (-8079 4000);
PAINT MONO (-8079 4000);
FORCEPROP 2 LAST PATH I55
J 2
(-8025 4050);
DISPLAY 1.021277 (-8025 4050);
DISPLAY INVISIBLE (-8025 4050);
FORCEPROP 1 LAST COMMENT_BODY TRUE
J 2
(-7780 3905);
DISPLAY 0.872340 (-7780 3905);
PAINT GREEN (-7780 3905);
DISPLAY INVISIBLE (-7780 3905);
FORCEPROP 1 LAST OFFPAGE TRUE
J 2
(-8150 3875);
DISPLAY 0.872340 (-8150 3875);
PAINT GREEN (-8150 3875);
DISPLAY INVISIBLE (-8150 3875);
FORCEPROP 2 LAST CDS_LIB standard
J 2
(-7825 4000);
DISPLAY INVISIBLE (-7825 4000);
FORCEADD Q_RES..1
R 2
(-6775 4000);
FORCEPROP 1 LAST LOCATION R430
J 0
(-6525 4000);
DISPLAY 0.489362 (-6525 4000);
PAINT SKYBLUE (-6525 4000);
FORCEPROP 0 LAST $SEC 1
J 2
(-6500 4050);
DISPLAY 0.680851 (-6500 4050);
PAINT MONO (-6500 4050);
DISPLAY INVISIBLE (-6500 4050);
FORCEPROP 0 LAST CDS_SEC 1
J 2
(-6500 4050);
DISPLAY 1.021277 (-6500 4050);
DISPLAY INVISIBLE (-6500 4050);
FORCEPROP 1 LASTPIN (-6675 4000) $PN 1
J 2
(-6687 4012);
DISPLAY 0.489362 (-6687 4012);
PAINT MONO (-6687 4012);
FORCEPROP 1 LASTPIN (-6875 4000) $PN 2
J 2
(-6837 4012);
DISPLAY 0.489362 (-6837 4012);
PAINT MONO (-6837 4012);
FORCEPROP 1 LAST VALUE 0
J 0
(-6675 4000);
DISPLAY 0.489362 (-6675 4000);
PAINT SKYBLUE (-6675 4000);
FORCEPROP 2 LAST CDS_LIB pure_quanta
J 2
(-6775 4000);
DISPLAY INVISIBLE (-6775 4000);
FORCEPROP 1 LAST PATH I57
J 2
(-6725 4150);
DISPLAY 0.978723 (-6725 4150);
PAINT WHITE (-6725 4150);
DISPLAY INVISIBLE (-6725 4150);
FORCEPROP 1 LAST WATTAGE 1/16W
J 0
(-7175 3925);
DISPLAY 0.489362 (-7175 3925);
PAINT SKYBLUE (-7175 3925);
DISPLAY INVISIBLE (-7175 3925);
FORCEPROP 1 LAST MATERIAL CHIP
J 2
(-7200 3925);
DISPLAY 0.489362 (-7200 3925);
PAINT SKYBLUE (-7200 3925);
DISPLAY INVISIBLE (-7200 3925);
FORCEPROP 1 LAST TOLERANCE 5%
J 2
(-6750 3925);
DISPLAY 0.489362 (-6750 3925);
PAINT SKYBLUE (-6750 3925);
DISPLAY INVISIBLE (-6750 3925);
FORCEPROP 1 LAST PART_NUMBER CS00002JB38
J 2
(-6800 4050);
DISPLAY 0.489362 (-6800 4050);
PAINT SKYBLUE (-6800 4050);
DISPLAY INVISIBLE (-6800 4050);
FORCEPROP 1 LAST PACK_TYPE 0402LF
J 2
(-6825 3925);
DISPLAY 0.489362 (-6825 3925);
PAINT SKYBLUE (-6825 3925);
DISPLAY INVISIBLE (-6825 3925);
FORCEADD OFFPAGE..3
R 2
(-7825 3950);
FORCEPROP 2 LAST $XR0 34 
J 0
(-8104 3950);
DISPLAY 0.638298 (-8104 3950);
PAINT MONO (-8104 3950);
FORCEPROP 2 LAST PATH I58
J 0
(-7775 4025);
DISPLAY 1.021277 (-7775 4025);
DISPLAY INVISIBLE (-7775 4025);
FORCEPROP 1 LAST COMMENT_BODY TRUE
J 2
(-7775 3850);
DISPLAY 0.872340 (-7775 3850);
PAINT PEACH (-7775 3850);
DISPLAY INVISIBLE (-7775 3850);
FORCEPROP 1 LAST OFFPAGE TRUE
J 2
(-8150 3825);
DISPLAY 0.872340 (-8150 3825);
PAINT GREEN (-8150 3825);
DISPLAY INVISIBLE (-8150 3825);
FORCEPROP 2 LAST CDS_LIB standard
J 0
(-7825 3950);
DISPLAY INVISIBLE (-7825 3950);
FORCEADD Q_CAP..1
(-2725 1150);
FORCEPROP 1 LAST LOCATION C216
J 0
(-2675 1250);
DISPLAY 0.489362 (-2675 1250);
PAINT SKYBLUE (-2675 1250);
FORCEPROP 0 LAST $SEC 1
J 0
(-2675 1300);
DISPLAY 0.680851 (-2675 1300);
PAINT MONO (-2675 1300);
DISPLAY INVISIBLE (-2675 1300);
FORCEPROP 0 LAST CDS_SEC 1
J 0
(-2675 1300);
DISPLAY 1.021277 (-2675 1300);
DISPLAY INVISIBLE (-2675 1300);
FORCEPROP 1 LASTPIN (-2725 1250) $PN 1
J 0
(-2715 1230);
DISPLAY 0.489362 (-2715 1230);
PAINT MONO (-2715 1230);
FORCEPROP 1 LASTPIN (-2725 1050) $PN 2
J 0
(-2715 1030);
DISPLAY 0.489362 (-2715 1030);
PAINT MONO (-2715 1030);
FORCEPROP 1 LAST PART_NUMBER TMP_QCH0106F0B00
J 0
(-2675 1000);
DISPLAY 0.489362 (-2675 1000);
PAINT SKYBLUE (-2675 1000);
FORCEPROP 1 LAST TOLERANCE 1%
J 0
(-2675 1100);
DISPLAY 0.489362 (-2675 1100);
PAINT SKYBLUE (-2675 1100);
FORCEPROP 1 LAST MATERIAL NPO
J 0
(-2675 1050);
DISPLAY 0.489362 (-2675 1050);
PAINT SKYBLUE (-2675 1050);
FORCEPROP 1 LAST PACK_TYPE 0402
J 0
(-2675 950);
DISPLAY 0.489362 (-2675 950);
PAINT SKYBLUE (-2675 950);
FORCEPROP 1 LAST VOLTAGE 50V
J 0
(-2675 1150);
DISPLAY 0.489362 (-2675 1150);
PAINT SKYBLUE (-2675 1150);
FORCEPROP 1 LAST VALUE 10PF
J 0
(-2675 1200);
DISPLAY 0.489362 (-2675 1200);
PAINT SKYBLUE (-2675 1200);
FORCEPROP 1 LAST PATH I6
J 0
(-2675 1300);
DISPLAY 0.978723 (-2675 1300);
PAINT WHITE (-2675 1300);
DISPLAY INVISIBLE (-2675 1300);
FORCEPROP 2 LAST CDS_LIB pure_quanta
J 0
(-2725 1150);
DISPLAY INVISIBLE (-2725 1150);
FORCEADD OFFPAGE..2
R 2
(-6725 4400);
FORCEPROP 2 LAST $XR1 136 
J 0
(-7099 4400);
DISPLAY 0.638298 (-7099 4400);
PAINT MONO (-7099 4400);
FORCEPROP 2 LAST $XR0 28 
J 0
(-6979 4400);
DISPLAY 0.638298 (-6979 4400);
PAINT MONO (-6979 4400);
FORCEPROP 2 LAST CDS_LIB standard
J 2
(-6725 4400);
DISPLAY INVISIBLE (-6725 4400);
FORCEPROP 1 LAST OFFPAGE TRUE
J 2
(-7050 4275);
DISPLAY 0.872340 (-7050 4275);
PAINT GREEN (-7050 4275);
DISPLAY INVISIBLE (-7050 4275);
FORCEPROP 1 LAST COMMENT_BODY TRUE
J 2
(-6680 4305);
DISPLAY 0.872340 (-6680 4305);
PAINT GREEN (-6680 4305);
DISPLAY INVISIBLE (-6680 4305);
FORCEPROP 2 LAST PATH I61
J 0
(-6925 4450);
DISPLAY 1.021277 (-6925 4450);
DISPLAY INVISIBLE (-6925 4450);
FORCEADD OFFPAGE..3
R 2
(-6725 4350);
FORCEPROP 2 LAST $XR1 136 
J 0
(-7094 4350);
DISPLAY 0.638298 (-7094 4350);
PAINT MONO (-7094 4350);
FORCEPROP 2 LAST $XR0 28 
J 0
(-6974 4350);
DISPLAY 0.638298 (-6974 4350);
PAINT MONO (-6974 4350);
FORCEPROP 2 LAST CDS_LIB standard
J 0
(-6725 4350);
DISPLAY INVISIBLE (-6725 4350);
FORCEPROP 1 LAST OFFPAGE TRUE
J 2
(-7050 4225);
DISPLAY 0.872340 (-7050 4225);
PAINT GREEN (-7050 4225);
DISPLAY INVISIBLE (-7050 4225);
FORCEPROP 1 LAST COMMENT_BODY TRUE
J 2
(-6675 4250);
DISPLAY 0.872340 (-6675 4250);
PAINT PEACH (-6675 4250);
DISPLAY INVISIBLE (-6675 4250);
FORCEPROP 2 LAST PATH I62
J 0
(-6950 4400);
DISPLAY 1.021277 (-6950 4400);
DISPLAY INVISIBLE (-6950 4400);
FORCEADD OFFPAGE..2
R 2
(-6725 4300);
FORCEPROP 2 LAST $XR1 136 
J 0
(-7099 4300);
DISPLAY 0.638298 (-7099 4300);
PAINT MONO (-7099 4300);
FORCEPROP 2 LAST $XR0 28 
J 0
(-6979 4300);
DISPLAY 0.638298 (-6979 4300);
PAINT MONO (-6979 4300);
FORCEPROP 2 LAST CDS_LIB standard
J 2
(-6725 4300);
DISPLAY INVISIBLE (-6725 4300);
FORCEPROP 1 LAST OFFPAGE TRUE
J 2
(-7050 4175);
DISPLAY 0.872340 (-7050 4175);
PAINT GREEN (-7050 4175);
DISPLAY INVISIBLE (-7050 4175);
FORCEPROP 1 LAST COMMENT_BODY TRUE
J 2
(-6680 4205);
DISPLAY 0.872340 (-6680 4205);
PAINT GREEN (-6680 4205);
DISPLAY INVISIBLE (-6680 4205);
FORCEPROP 2 LAST PATH I65
J 0
(-6925 4350);
DISPLAY 1.021277 (-6925 4350);
DISPLAY INVISIBLE (-6925 4350);
FORCEADD OFFPAGE..3
R 2
(-6725 4250);
FORCEPROP 2 LAST $XR1 136 
J 0
(-7094 4250);
DISPLAY 0.638298 (-7094 4250);
PAINT MONO (-7094 4250);
FORCEPROP 2 LAST $XR0 28 
J 0
(-6974 4250);
DISPLAY 0.638298 (-6974 4250);
PAINT MONO (-6974 4250);
FORCEPROP 2 LAST CDS_LIB standard
J 0
(-6725 4250);
DISPLAY INVISIBLE (-6725 4250);
FORCEPROP 1 LAST OFFPAGE TRUE
J 2
(-7050 4125);
DISPLAY 0.872340 (-7050 4125);
PAINT GREEN (-7050 4125);
DISPLAY INVISIBLE (-7050 4125);
FORCEPROP 1 LAST COMMENT_BODY TRUE
J 2
(-6675 4150);
DISPLAY 0.872340 (-6675 4150);
PAINT PEACH (-6675 4150);
DISPLAY INVISIBLE (-6675 4150);
FORCEPROP 2 LAST PATH I66
J 0
(-6950 4300);
DISPLAY 1.021277 (-6950 4300);
DISPLAY INVISIBLE (-6950 4300);
FORCEADD OFFPAGE..2
R 2
(-7200 3450);
FORCEPROP 2 LAST $XR1 80 
J 0
(-7514 3450);
DISPLAY 0.638298 (-7514 3450);
PAINT MONO (-7514 3450);
FORCEPROP 2 LAST $XR0 28 
J 0
(-7424 3450);
DISPLAY 0.638298 (-7424 3450);
PAINT MONO (-7424 3450);
FORCEPROP 2 LAST CDS_LIB standard
J 2
(-7200 3450);
DISPLAY INVISIBLE (-7200 3450);
FORCEPROP 1 LAST OFFPAGE TRUE
J 2
(-7525 3325);
DISPLAY 0.872340 (-7525 3325);
PAINT GREEN (-7525 3325);
DISPLAY INVISIBLE (-7525 3325);
FORCEPROP 1 LAST COMMENT_BODY TRUE
J 2
(-7155 3355);
DISPLAY 0.872340 (-7155 3355);
PAINT GREEN (-7155 3355);
DISPLAY INVISIBLE (-7155 3355);
FORCEPROP 2 LAST PATH I68
J 0
(-7400 3500);
DISPLAY 1.021277 (-7400 3500);
DISPLAY INVISIBLE (-7400 3500);
FORCEADD OFFPAGE..1
(-7825 4850);
FORCEPROP 2 LAST $XR1 81 
J 0
(-8166 4850);
DISPLAY 0.638298 (-8166 4850);
PAINT MONO (-8166 4850);
FORCEPROP 2 LAST $XR0 28 
J 0
(-8076 4850);
DISPLAY 0.638298 (-8076 4850);
PAINT MONO (-8076 4850);
FORCEPROP 2 LAST CDS_LIB standard
J 0
(-7825 4850);
DISPLAY INVISIBLE (-7825 4850);
FORCEPROP 1 LAST OFFPAGE TRUE
J 0
(-7500 4725);
DISPLAY 0.872340 (-7500 4725);
PAINT GREEN (-7500 4725);
DISPLAY INVISIBLE (-7500 4725);
FORCEPROP 1 LAST COMMENT_BODY TRUE
J 0
(-7700 4750);
DISPLAY 0.872340 (-7700 4750);
PAINT GREEN (-7700 4750);
DISPLAY INVISIBLE (-7700 4750);
FORCEPROP 2 LAST PATH I69
J 0
(-7775 4925);
DISPLAY 1.021277 (-7775 4925);
DISPLAY INVISIBLE (-7775 4925);
FORCEADD UNIVERSAL_GND..1
(-2725 800);
FORCEPROP 3 LASTPIN (-2725 850) SIG_NAME GND\g
J 0
(-2715 860);
DISPLAY 0.659574 (-2715 860);
PAINT MONO (-2715 860);
DISPLAY INVISIBLE (-2715 860);
FORCEPROP 2 LAST CDS_LIB pure_quanta_power
J 0
(-2725 800);
DISPLAY INVISIBLE (-2725 800);
FORCEPROP 1 LAST PATH I7
J 0
(-2650 800);
DISPLAY 0.872340 (-2650 800);
PAINT AQUA (-2650 800);
DISPLAY INVISIBLE (-2650 800);
FORCEPROP 1 LAST HDL_POWER GND
J 1
(-2700 725);
DISPLAY 0.872340 (-2700 725);
PAINT GREEN (-2700 725);
DISPLAY INVISIBLE (-2700 725);
FORCEADD OFFPAGE..1
(-6300 5600);
FORCEPROP 2 LAST $XR1 80 
J 0
(-6611 5600);
DISPLAY 0.638298 (-6611 5600);
PAINT MONO (-6611 5600);
FORCEPROP 2 LAST $XR0 28 
J 0
(-6521 5600);
DISPLAY 0.638298 (-6521 5600);
PAINT MONO (-6521 5600);
FORCEPROP 2 LAST CDS_LIB standard
J 0
(-6300 5600);
DISPLAY INVISIBLE (-6300 5600);
FORCEPROP 1 LAST OFFPAGE TRUE
J 0
(-5975 5475);
DISPLAY 0.872340 (-5975 5475);
PAINT GREEN (-5975 5475);
DISPLAY INVISIBLE (-5975 5475);
FORCEPROP 1 LAST COMMENT_BODY TRUE
J 0
(-6175 5500);
DISPLAY 0.872340 (-6175 5500);
PAINT GREEN (-6175 5500);
DISPLAY INVISIBLE (-6175 5500);
FORCEPROP 2 LAST PATH I72
J 0
(-6500 5650);
DISPLAY 1.021277 (-6500 5650);
DISPLAY INVISIBLE (-6500 5650);
FORCEADD Q_RES..2
(-8700 6125);
FORCEPROP 1 LAST LOCATION R422
J 0
(-8850 6225);
DISPLAY 0.489362 (-8850 6225);
PAINT SKYBLUE (-8850 6225);
FORCEPROP 0 LAST $SEC 1
J 0
(-8650 6275);
DISPLAY 0.680851 (-8650 6275);
PAINT MONO (-8650 6275);
DISPLAY INVISIBLE (-8650 6275);
FORCEPROP 0 LAST CDS_SEC 1
J 0
(-8650 6275);
DISPLAY 1.021277 (-8650 6275);
DISPLAY INVISIBLE (-8650 6275);
FORCEPROP 1 LASTPIN (-8700 6225) $PN 1
J 0
(-8695 6187);
DISPLAY 0.489362 (-8695 6187);
PAINT MONO (-8695 6187);
FORCEPROP 1 LASTPIN (-8700 6025) $PN 2
J 0
(-8695 6035);
DISPLAY 0.489362 (-8695 6035);
PAINT MONO (-8695 6035);
FORCEPROP 1 LAST PART_NUMBER CS22202JB07
J 0
(-8975 6125);
DISPLAY 0.489362 (-8975 6125);
PAINT SKYBLUE (-8975 6125);
FORCEPROP 1 LAST VALUE 2.2K
J 0
(-8850 6175);
DISPLAY 0.489362 (-8850 6175);
PAINT SKYBLUE (-8850 6175);
FORCEPROP 1 LAST PACK_TYPE 0402LF
J 0
(-8650 6075);
DISPLAY 0.489362 (-8650 6075);
PAINT SKYBLUE (-8650 6075);
DISPLAY INVISIBLE (-8650 6075);
FORCEPROP 1 LAST WATTAGE 1/16W
J 0
(-8650 6125);
DISPLAY 0.489362 (-8650 6125);
PAINT SKYBLUE (-8650 6125);
DISPLAY INVISIBLE (-8650 6125);
FORCEPROP 1 LAST PATH I75
J 0
(-8650 6300);
DISPLAY 0.978723 (-8650 6300);
PAINT WHITE (-8650 6300);
DISPLAY INVISIBLE (-8650 6300);
FORCEPROP 2 LAST CDS_LIB pure_quanta
J 0
(-8700 6125);
DISPLAY INVISIBLE (-8700 6125);
FORCEPROP 1 LAST TOLERANCE 5%
J 0
(-8650 6150);
DISPLAY 0.489362 (-8650 6150);
PAINT SKYBLUE (-8650 6150);
DISPLAY INVISIBLE (-8650 6150);
FORCEPROP 1 LAST MATERIAL CHIP
J 0
(-8850 6125);
DISPLAY 0.489362 (-8850 6125);
PAINT SKYBLUE (-8850 6125);
DISPLAY INVISIBLE (-8850 6125);
FORCEADD OFFPAGE..2
(-7625 5950);
FORCEPROP 2 LAST $XR1 80 
J 0
(-7346 5950);
DISPLAY 0.638298 (-7346 5950);
PAINT MONO (-7346 5950);
FORCEPROP 2 LAST $XR0 28 
J 0
(-7436 5950);
DISPLAY 0.638298 (-7436 5950);
PAINT MONO (-7436 5950);
FORCEPROP 2 LAST CDS_LIB standard
J 2
(-7625 5950);
DISPLAY INVISIBLE (-7625 5950);
FORCEPROP 1 LAST OFFPAGE TRUE
J 0
(-7300 5825);
DISPLAY 0.872340 (-7300 5825);
PAINT GREEN (-7300 5825);
DISPLAY INVISIBLE (-7300 5825);
FORCEPROP 1 LAST COMMENT_BODY TRUE
J 0
(-7670 5855);
DISPLAY 0.872340 (-7670 5855);
PAINT GREEN (-7670 5855);
DISPLAY INVISIBLE (-7670 5855);
FORCEPROP 2 LAST PATH I78
J 2
(-7675 6025);
DISPLAY 1.021277 (-7675 6025);
DISPLAY INVISIBLE (-7675 6025);
FORCEADD UNIVERSAL_POWER..1
(-8525 6425);
FORCEPROP 3 LASTPIN (-8525 6375) SIG_NAME PVDD18_S5_P0\g
J 0
(-8515 6385);
DISPLAY 0.659574 (-8515 6385);
PAINT MONO (-8515 6385);
DISPLAY INVISIBLE (-8515 6385);
FORCEPROP 1 LAST HDL_POWER PVDD18_S5_P0
J 1
(-8525 6475);
DISPLAY 0.489362 (-8525 6475);
PAINT GREEN (-8525 6475);
FORCEPROP 2 LAST CDS_LIB pure_quanta_power
J 0
(-8525 6425);
DISPLAY INVISIBLE (-8525 6425);
FORCEPROP 1 LAST PATH I79
J 0
(-8475 6450);
DISPLAY 0.872340 (-8475 6450);
PAINT AQUA (-8475 6450);
DISPLAY INVISIBLE (-8475 6450);
FORCEADD Q_RES..1
(-3275 1525);
FORCEPROP 1 LAST LOCATION R433
J 0
(-3350 1575);
DISPLAY 0.489362 (-3350 1575);
PAINT SKYBLUE (-3350 1575);
FORCEPROP 0 LAST $SEC 1
J 0
(-3325 1700);
DISPLAY 0.680851 (-3325 1700);
PAINT MONO (-3325 1700);
DISPLAY INVISIBLE (-3325 1700);
FORCEPROP 0 LAST CDS_SEC 1
J 0
(-3325 1700);
DISPLAY 1.021277 (-3325 1700);
DISPLAY INVISIBLE (-3325 1700);
FORCEPROP 1 LASTPIN (-3375 1525) $PN 1
J 0
(-3363 1537);
DISPLAY 0.489362 (-3363 1537);
PAINT MONO (-3363 1537);
FORCEPROP 1 LASTPIN (-3175 1525) $PN 2
J 0
(-3213 1537);
DISPLAY 0.489362 (-3213 1537);
PAINT MONO (-3213 1537);
FORCEPROP 1 LAST MATERIAL CHIP
J 0
(-3275 1375);
DISPLAY 0.489362 (-3275 1375);
PAINT SKYBLUE (-3275 1375);
FORCEPROP 1 LAST PART_NUMBER CS62002JB18
J 0
(-3350 1650);
DISPLAY 0.489362 (-3350 1650);
PAINT SKYBLUE (-3350 1650);
FORCEPROP 1 LAST WATTAGE 1/16W
J 2
(-3300 1375);
DISPLAY 0.489362 (-3300 1375);
PAINT SKYBLUE (-3300 1375);
FORCEPROP 1 LAST TOLERANCE 5%
J 0
(-3275 1425);
DISPLAY 0.489362 (-3275 1425);
PAINT SKYBLUE (-3275 1425);
FORCEPROP 1 LAST VALUE 20M
J 2
(-3300 1425);
DISPLAY 0.489362 (-3300 1425);
PAINT SKYBLUE (-3300 1425);
FORCEPROP 1 LAST PACK_TYPE 0402LF
J 0
(-3025 1375);
DISPLAY 0.489362 (-3025 1375);
PAINT SKYBLUE (-3025 1375);
FORCEPROP 2 LAST CDS_LIB pure_quanta
J 0
(-3275 1525);
DISPLAY INVISIBLE (-3275 1525);
FORCEPROP 1 LAST PATH I8
J 0
(-3325 1675);
DISPLAY 0.978723 (-3325 1675);
PAINT WHITE (-3325 1675);
DISPLAY INVISIBLE (-3325 1675);
FORCEADD OFFPAGE..1
(-6300 5550);
FORCEPROP 2 LAST $XR1 80 
J 0
(-6611 5550);
DISPLAY 0.638298 (-6611 5550);
PAINT MONO (-6611 5550);
FORCEPROP 2 LAST $XR0 28 
J 0
(-6521 5550);
DISPLAY 0.638298 (-6521 5550);
PAINT MONO (-6521 5550);
FORCEPROP 2 LAST CDS_LIB standard
J 0
(-6300 5550);
DISPLAY INVISIBLE (-6300 5550);
FORCEPROP 1 LAST OFFPAGE TRUE
J 0
(-5975 5425);
DISPLAY 0.872340 (-5975 5425);
PAINT GREEN (-5975 5425);
DISPLAY INVISIBLE (-5975 5425);
FORCEPROP 1 LAST COMMENT_BODY TRUE
J 0
(-6175 5450);
DISPLAY 0.872340 (-6175 5450);
PAINT GREEN (-6175 5450);
DISPLAY INVISIBLE (-6175 5450);
FORCEPROP 2 LAST PATH I80
J 0
(-6250 5625);
DISPLAY 1.021277 (-6250 5625);
DISPLAY INVISIBLE (-6250 5625);
FORCEADD OFFPAGE..2
(-7625 5900);
FORCEPROP 2 LAST $XR1 80 
J 0
(-7346 5900);
DISPLAY 0.638298 (-7346 5900);
PAINT MONO (-7346 5900);
FORCEPROP 2 LAST $XR0 28 
J 0
(-7436 5900);
DISPLAY 0.638298 (-7436 5900);
PAINT MONO (-7436 5900);
FORCEPROP 2 LAST CDS_LIB standard
J 0
(-7625 5900);
DISPLAY INVISIBLE (-7625 5900);
FORCEPROP 1 LAST OFFPAGE TRUE
J 0
(-7300 5775);
DISPLAY 0.872340 (-7300 5775);
PAINT GREEN (-7300 5775);
DISPLAY INVISIBLE (-7300 5775);
FORCEPROP 1 LAST COMMENT_BODY TRUE
J 0
(-7670 5805);
DISPLAY 0.872340 (-7670 5805);
PAINT GREEN (-7670 5805);
DISPLAY INVISIBLE (-7670 5805);
FORCEPROP 2 LAST PATH I81
J 0
(-7450 5975);
DISPLAY 1.021277 (-7450 5975);
DISPLAY INVISIBLE (-7450 5975);
FORCEADD UNIVERSAL_GND..1
(-9050 5025);
FORCEPROP 3 LASTPIN (-9050 5075) SIG_NAME GND\g
J 0
(-9040 5085);
DISPLAY 0.659574 (-9040 5085);
PAINT MONO (-9040 5085);
DISPLAY INVISIBLE (-9040 5085);
FORCEPROP 2 LAST CDS_LIB pure_quanta_power
J 2
(-9050 5025);
DISPLAY INVISIBLE (-9050 5025);
FORCEPROP 1 LAST PATH I82
J 0
(-8975 5025);
DISPLAY 0.872340 (-8975 5025);
PAINT AQUA (-8975 5025);
DISPLAY INVISIBLE (-8975 5025);
FORCEPROP 1 LAST HDL_POWER GND
J 1
(-9025 4950);
DISPLAY 0.702128 (-9025 4950);
PAINT GREEN (-9025 4950);
DISPLAY INVISIBLE (-9025 4950);
FORCEADD CONN6_HBC1031L200D8H..1
R 2
(-8675 5300);
FORCEPROP 1 LAST LOCATION J6
J 0
(-8800 5525);
DISPLAY 0.489362 (-8800 5525);
PAINT SKYBLUE (-8800 5525);
FORCEPROP 2 LAST $SEC 1
J 0
(-8800 5775);
DISPLAY 0.680851 (-8800 5775);
PAINT MONO (-8800 5775);
DISPLAY INVISIBLE (-8800 5775);
FORCEPROP 0 LAST CDS_SEC 1
J 0
(-8800 5775);
DISPLAY 1.021277 (-8800 5775);
DISPLAY INVISIBLE (-8800 5775);
FORCEPROP 2 LASTPIN (-8400 5400) $PN 1
J 0
(-8390 5410);
DISPLAY 0.489362 (-8390 5410);
PAINT MONO (-8390 5410);
FORCEPROP 2 LASTPIN (-8950 5400) $PN 2
J 2
(-8960 5410);
DISPLAY 0.489362 (-8960 5410);
PAINT MONO (-8960 5410);
FORCEPROP 2 LASTPIN (-8400 5300) $PN 3
J 0
(-8390 5310);
DISPLAY 0.489362 (-8390 5310);
PAINT MONO (-8390 5310);
FORCEPROP 2 LASTPIN (-8950 5300) $PN 4
J 2
(-8960 5310);
DISPLAY 0.489362 (-8960 5310);
PAINT MONO (-8960 5310);
FORCEPROP 2 LASTPIN (-8400 5200) $PN 5
J 0
(-8390 5210);
DISPLAY 0.489362 (-8390 5210);
PAINT MONO (-8390 5210);
FORCEPROP 2 LASTPIN (-8950 5200) $PN 6
J 2
(-8960 5210);
DISPLAY 0.489362 (-8960 5210);
PAINT MONO (-8960 5210);
FORCEPROP 2 LAST VALUE CONN6_HBC1031-L200D-8H
J 0
(-8800 5675);
DISPLAY 0.489362 (-8800 5675);
PAINT SKYBLUE (-8800 5675);
FORCEPROP 1 LAST MATERIAL IO
J 0
(-8800 5457);
DISPLAY 0.489362 (-8800 5457);
PAINT SKYBLUE (-8800 5457);
FORCEPROP 1 LAST PART_NUMBER DFHD06MS263
J 0
(-8800 5584);
DISPLAY 0.489362 (-8800 5584);
PAINT SKYBLUE (-8800 5584);
FORCEPROP 2 LAST PART_TYPE THLF
J 0
(-8800 5725);
DISPLAY 1.021277 (-8800 5725);
FORCEPROP 1 LAST CDS_LMAN_SYM_OUTLINE -125,150,125,-150
J 2
(-8675 5300);
DISPLAY 0.468085 (-8675 5300);
PAINT GREEN (-8675 5300);
DISPLAY INVISIBLE (-8675 5300);
FORCEPROP 1 LAST NEEDS_NO_SIZE TRUE
J 2
(-8675 5300);
DISPLAY 0.723404 (-8675 5300);
PAINT GREEN (-8675 5300);
DISPLAY INVISIBLE (-8675 5300);
FORCEPROP 2 LAST CDS_LIB pure_quanta
J 0
(-8675 5300);
DISPLAY INVISIBLE (-8675 5300);
FORCEPROP 1 LAST PATH I83
J 2
(-8675 5300);
DISPLAY 0.723404 (-8675 5300);
PAINT GREEN (-8675 5300);
DISPLAY INVISIBLE (-8675 5300);
FORCEADD OFFPAGE..5
R 2
(-7750 5400);
FORCEPROP 2 LAST $XR1 80 
J 0
(-7471 5400);
DISPLAY 0.638298 (-7471 5400);
PAINT MONO (-7471 5400);
FORCEPROP 2 LAST $XR0 28 
J 0
(-7561 5400);
DISPLAY 0.638298 (-7561 5400);
PAINT MONO (-7561 5400);
FORCEPROP 2 LAST CDS_LIB standard
J 0
(-7750 5400);
DISPLAY INVISIBLE (-7750 5400);
FORCEPROP 2 LAST BOM_COST SYS_CLOCK
J 2
(-7950 5500);
DISPLAY 0.808511 (-7950 5500);
DISPLAY INVISIBLE (-7950 5500);
FORCEPROP 1 LAST OFFPAGE TRUE
J 2
(-8075 5275);
DISPLAY 0.872340 (-8075 5275);
PAINT GREEN (-8075 5275);
DISPLAY INVISIBLE (-8075 5275);
FORCEPROP 1 LAST COMMENT_BODY TRUE
J 2
(-7850 5325);
DISPLAY 0.872340 (-7850 5325);
PAINT GREEN (-7850 5325);
DISPLAY INVISIBLE (-7850 5325);
FORCEPROP 2 LAST PATH I84
J 2
(-7800 5475);
DISPLAY 1.021277 (-7800 5475);
DISPLAY INVISIBLE (-7800 5475);
FORCEPROP 2 LAST ROOM DB2000_2_NVME
J 2
(-7950 5450);
DISPLAY 0.808511 (-7950 5450);
PAINT RED (-7950 5450);
DISPLAY INVISIBLE (-7950 5450);
FORCEADD OFFPAGE..5
R 2
(-7750 5300);
FORCEPROP 2 LAST $XR1 80 
J 0
(-7471 5300);
DISPLAY 0.638298 (-7471 5300);
PAINT MONO (-7471 5300);
FORCEPROP 2 LAST $XR0 28 
J 0
(-7561 5300);
DISPLAY 0.638298 (-7561 5300);
PAINT MONO (-7561 5300);
FORCEPROP 2 LAST BOM_COST SYS_CLOCK
J 2
(-7950 5400);
DISPLAY 0.808511 (-7950 5400);
DISPLAY INVISIBLE (-7950 5400);
FORCEPROP 2 LAST CDS_LIB standard
J 2
(-7750 5300);
DISPLAY INVISIBLE (-7750 5300);
FORCEPROP 1 LAST OFFPAGE TRUE
J 2
(-8075 5175);
DISPLAY 0.872340 (-8075 5175);
PAINT GREEN (-8075 5175);
DISPLAY INVISIBLE (-8075 5175);
FORCEPROP 1 LAST COMMENT_BODY TRUE
J 2
(-7850 5225);
DISPLAY 0.872340 (-7850 5225);
PAINT GREEN (-7850 5225);
DISPLAY INVISIBLE (-7850 5225);
FORCEPROP 2 LAST PATH I85
J 2
(-7800 5375);
DISPLAY 1.021277 (-7800 5375);
DISPLAY INVISIBLE (-7800 5375);
FORCEPROP 2 LAST ROOM DB2000_2_NVME
J 2
(-7950 5350);
DISPLAY 0.808511 (-7950 5350);
PAINT RED (-7950 5350);
DISPLAY INVISIBLE (-7950 5350);
FORCEADD OFFPAGE..1
(-6300 5500);
FORCEPROP 2 LAST $XR1 80 
J 0
(-6611 5500);
DISPLAY 0.638298 (-6611 5500);
PAINT MONO (-6611 5500);
FORCEPROP 2 LAST $XR0 28 
J 0
(-6521 5500);
DISPLAY 0.638298 (-6521 5500);
PAINT MONO (-6521 5500);
FORCEPROP 2 LAST CDS_LIB standard
J 0
(-6300 5500);
DISPLAY INVISIBLE (-6300 5500);
FORCEPROP 1 LAST OFFPAGE TRUE
J 0
(-5975 5375);
DISPLAY 0.872340 (-5975 5375);
PAINT GREEN (-5975 5375);
DISPLAY INVISIBLE (-5975 5375);
FORCEPROP 1 LAST COMMENT_BODY TRUE
J 0
(-6175 5400);
DISPLAY 0.872340 (-6175 5400);
PAINT GREEN (-6175 5400);
DISPLAY INVISIBLE (-6175 5400);
FORCEPROP 2 LAST PATH I86
J 0
(-6250 5575);
DISPLAY 1.021277 (-6250 5575);
DISPLAY INVISIBLE (-6250 5575);
FORCEADD OFFPAGE..1
(-6300 5400);
FORCEPROP 2 LAST $XR1 80 
J 0
(-6611 5400);
DISPLAY 0.638298 (-6611 5400);
PAINT MONO (-6611 5400);
FORCEPROP 2 LAST $XR0 28 
J 0
(-6521 5400);
DISPLAY 0.638298 (-6521 5400);
PAINT MONO (-6521 5400);
FORCEPROP 2 LAST CDS_LIB standard
J 0
(-6300 5400);
DISPLAY INVISIBLE (-6300 5400);
FORCEPROP 1 LAST OFFPAGE TRUE
J 0
(-5975 5275);
DISPLAY 0.872340 (-5975 5275);
PAINT GREEN (-5975 5275);
DISPLAY INVISIBLE (-5975 5275);
FORCEPROP 1 LAST COMMENT_BODY TRUE
J 0
(-6175 5300);
DISPLAY 0.872340 (-6175 5300);
PAINT GREEN (-6175 5300);
DISPLAY INVISIBLE (-6175 5300);
FORCEPROP 2 LAST PATH I87
J 0
(-6250 5475);
DISPLAY 1.021277 (-6250 5475);
DISPLAY INVISIBLE (-6250 5475);
FORCEADD OFFPAGE..2
(-2200 2250);
FORCEPROP 2 LAST $XR0 28 
J 0
(-2011 2250);
DISPLAY 0.638298 (-2011 2250);
PAINT MONO (-2011 2250);
FORCEPROP 2 LAST CDS_LIB standard
J 2
(-2200 2250);
DISPLAY INVISIBLE (-2200 2250);
FORCEPROP 1 LAST OFFPAGE TRUE
J 0
(-1875 2125);
DISPLAY 0.872340 (-1875 2125);
PAINT GREEN (-1875 2125);
DISPLAY INVISIBLE (-1875 2125);
FORCEPROP 1 LAST COMMENT_BODY TRUE
J 0
(-2245 2155);
DISPLAY 0.872340 (-2245 2155);
PAINT GREEN (-2245 2155);
DISPLAY INVISIBLE (-2245 2155);
FORCEPROP 2 LAST PATH I9
J 2
(-2250 2325);
DISPLAY 1.021277 (-2250 2325);
DISPLAY INVISIBLE (-2250 2325);
FORCEADD DNS..2
(-7275 450);
PAINT RED (-7275 450);
FORCEPROP 2 LAST BOM_COST OCP3.0 
J 0
(-7400 575);
DISPLAY 0.680851 (-7400 575);
DISPLAY INVISIBLE (-7400 575);
FORCEPROP 2 LAST CDS_LIB mstr_misc
J 0
(-7275 450);
DISPLAY INVISIBLE (-7275 450);
FORCEPROP 1 LAST COMMENT_BODY TRUE
J 0
(-7275 450);
DISPLAY 0.744681 (-7275 450);
DISPLAY INVISIBLE (-7275 450);
FORCEADD DNS..2
(-8650 2700);
PAINT RED (-8650 2700);
FORCEPROP 1 LAST COMMENT_BODY TRUE
J 0
(-8650 2700);
DISPLAY 0.744681 (-8650 2700);
DISPLAY INVISIBLE (-8650 2700);
FORCEPROP 2 LAST BOM_COST OCP3.0 
J 0
(-8775 2825);
DISPLAY 0.680851 (-8775 2825);
DISPLAY INVISIBLE (-8775 2825);
FORCEPROP 2 LAST CDS_LIB mstr_misc
J 0
(-8650 2700);
DISPLAY INVISIBLE (-8650 2700);
FORCEADD DNS..2
(-8825 2700);
PAINT RED (-8825 2700);
FORCEPROP 1 LAST COMMENT_BODY TRUE
J 0
(-8825 2700);
DISPLAY 0.744681 (-8825 2700);
DISPLAY INVISIBLE (-8825 2700);
FORCEPROP 2 LAST BOM_COST OCP3.0 
J 0
(-8950 2825);
DISPLAY 0.680851 (-8950 2825);
DISPLAY INVISIBLE (-8950 2825);
FORCEPROP 2 LAST CDS_LIB mstr_misc
J 0
(-8825 2700);
DISPLAY INVISIBLE (-8825 2700);
FORCEADD DNS..2
(-7700 1475);
PAINT RED (-7700 1475);
FORCEPROP 2 LAST BOM_COST OCP3.0 
J 0
(-7825 1600);
DISPLAY 0.680851 (-7825 1600);
DISPLAY INVISIBLE (-7825 1600);
FORCEPROP 2 LAST CDS_LIB mstr_misc
J 0
(-7700 1475);
DISPLAY INVISIBLE (-7700 1475);
FORCEPROP 1 LAST COMMENT_BODY TRUE
J 0
(-7700 1475);
DISPLAY 0.744681 (-7700 1475);
DISPLAY INVISIBLE (-7700 1475);
FORCEADD DNS..2
(-9025 2700);
PAINT RED (-9025 2700);
FORCEPROP 1 LAST COMMENT_BODY TRUE
J 0
(-9025 2700);
DISPLAY 0.744681 (-9025 2700);
DISPLAY INVISIBLE (-9025 2700);
FORCEPROP 2 LAST BOM_COST OCP3.0 
J 0
(-9150 2825);
DISPLAY 0.680851 (-9150 2825);
DISPLAY INVISIBLE (-9150 2825);
FORCEPROP 2 LAST CDS_LIB mstr_misc
J 0
(-9025 2700);
DISPLAY INVISIBLE (-9025 2700);
FORCEADD QUANTA_TITLE_BLOCK_C..1
(0 0);
FORCEPROP 0 LAST CDS_CON_LAST_MODIFIED Fri Mar 11 14:52:22 2022
J 0
(-1885 15);
DISPLAY INVISIBLE (-1885 15);
FORCEPROP 1 LAST CUSTOM_TXT_CDS <CON_LAST_MODIFIED>
J 0
(-1885 15);
DISPLAY 0.978723 (-1885 15);
FORCEPROP 2 LAST CUSTOM_TXT_CDS <XR_PAGE_TITLE>
J 0
(-7890 5250);
DISPLAY 0.638298 (-7890 5250);
PAINT PINK (-7890 5250);
DISPLAY INVISIBLE (-7890 5250);
FORCEPROP 1 LAST CUSTOM_TXT_CDS <NAME_2>
J 0
(-3175 50);
FORCEPROP 1 LAST CUSTOM_TXT_CDS <NAME_1>
J 0
(-3175 175);
FORCEPROP 1 LAST CUSTOM_TXT_CDS <Q_NUMBER>
J 0
(-1403 103);
DISPLAY 1.212766 (-1403 103);
FORCEPROP 1 LAST CUSTOM_TXT_CDS <Q_PROJ>
J 0
(-2382 102);
DISPLAY 1.212766 (-2382 102);
FORCEPROP 1 LAST CUSTOM_TXT_CDS <Q_REV>
J 0
(-184 103);
DISPLAY 1.212766 (-184 103);
FORCEPROP 1 LAST CUSTOM_TXT_CDS <CON_PAGE_NUM> OF <CON_TOTAL_PAGES>
J 0
(-446 18);
DISPLAY 0.978723 (-446 18);
FORCEPROP 1 LAST Q_TITLE CPU0 MISC 2/2
J 0
(-9300 50);
DISPLAY 2.446809 (-9300 50);
PAINT GREEN (-9300 50);
FORCEPROP 1 LAST Q_DEPT BU9
J 1
(-3763 49);
DISPLAY 1.957447 (-3763 49);
PAINT GREEN (-3763 49);
FORCEPROP 2 LAST PAGE_BORDER TRUE
J 0
(-7890 5250);
DISPLAY 0.638298 (-7890 5250);
PAINT PINK (-7890 5250);
DISPLAY INVISIBLE (-7890 5250);
FORCEPROP 1 LAST CDS_LMAN_SYM_OUTLINE -9475,6775,100,-125
J 0
(0 0);
DISPLAY 0.468085 (0 0);
PAINT GREEN (0 0);
DISPLAY INVISIBLE (0 0);
FORCEPROP 2 LAST CDS_LIB pure_quanta
J 0
(0 0);
DISPLAY INVISIBLE (0 0);
FORCEPROP 1 LAST COMMENT_BODY TRUE
J 0
(12 -13);
DISPLAY 0.978723 (12 -13);
PAINT GREEN (12 -13);
DISPLAY INVISIBLE (12 -13);
FORCEPROP 2 LAST CDS_XR_PAGE_TITLE CR-28 : @T6G_MB_LIB.T6G(SCH_1):PAGE28
J 0
(-7890 5250);
DISPLAY 0.638298 (-7890 5250);
PAINT PINK (-7890 5250);
DISPLAY INVISIBLE (-7890 5250);
FORCEADD DNS..2
(-7775 875);
PAINT RED (-7775 875);
FORCEPROP 2 LAST CDS_LIB mstr_misc
J 0
(-7775 875);
DISPLAY INVISIBLE (-7775 875);
FORCEPROP 1 LAST COMMENT_BODY TRUE
J 0
(-7775 875);
DISPLAY 0.744681 (-7775 875);
DISPLAY INVISIBLE (-7775 875);
FORCEPROP 2 LAST BOM_COST OCP3.0 
J 0
(-7900 1000);
DISPLAY 0.680851 (-7900 1000);
DISPLAY INVISIBLE (-7900 1000);
FORCEADD DNS..2
(-7500 475);
PAINT RED (-7500 475);
FORCEPROP 2 LAST BOM_COST OCP3.0 
J 0
(-7625 600);
DISPLAY 0.680851 (-7625 600);
DISPLAY INVISIBLE (-7625 600);
FORCEPROP 2 LAST CDS_LIB mstr_misc
J 0
(-7500 475);
DISPLAY INVISIBLE (-7500 475);
FORCEPROP 1 LAST COMMENT_BODY TRUE
J 0
(-7500 475);
DISPLAY 0.744681 (-7500 475);
DISPLAY INVISIBLE (-7500 475);
FORCEADD DNS..2
(-7300 825);
PAINT RED (-7300 825);
FORCEPROP 2 LAST CDS_LIB mstr_misc
J 0
(-7300 825);
DISPLAY INVISIBLE (-7300 825);
FORCEPROP 2 LAST BOM_COST OCP3.0 
J 0
(-7425 950);
DISPLAY 0.680851 (-7425 950);
DISPLAY INVISIBLE (-7425 950);
FORCEPROP 1 LAST COMMENT_BODY TRUE
J 0
(-7300 825);
DISPLAY 0.744681 (-7300 825);
DISPLAY INVISIBLE (-7300 825);
FORCEADD DESIGN_NOTE..1
(-7975 6325);
FORCEPROP 0 LAST L1 RST_SYS PU BY STRAP PIN
J 0
(-8175 6200);
DISPLAY 0.808511 (-8175 6200);
PAINT WHITE (-8175 6200);
FORCEPROP 2 LAST CDS_LIB pure_quanta_power
J 0
(-7975 6325);
DISPLAY INVISIBLE (-7975 6325);
FORCEPROP 1 LAST COMMENT_BODY TRUE
J 0
(-7950 6425);
DISPLAY 0.978723 (-7950 6425);
DISPLAY INVISIBLE (-7950 6425);
FORCEADD DNS..2
(-8475 2700);
PAINT RED (-8475 2700);
FORCEPROP 2 LAST BOM_COST OCP3.0 
J 0
(-8600 2825);
DISPLAY 0.680851 (-8600 2825);
DISPLAY INVISIBLE (-8600 2825);
FORCEPROP 1 LAST COMMENT_BODY TRUE
J 0
(-8475 2700);
DISPLAY 0.744681 (-8475 2700);
DISPLAY INVISIBLE (-8475 2700);
FORCEPROP 2 LAST CDS_LIB mstr_misc
J 0
(-8475 2700);
DISPLAY INVISIBLE (-8475 2700);
FORCEADD DNS..2
(-7750 500);
PAINT RED (-7750 500);
FORCEPROP 2 LAST CDS_LIB mstr_misc
J 0
(-7750 500);
DISPLAY INVISIBLE (-7750 500);
FORCEPROP 2 LAST BOM_COST OCP3.0 
J 0
(-7875 625);
DISPLAY 0.680851 (-7875 625);
DISPLAY INVISIBLE (-7875 625);
FORCEPROP 1 LAST COMMENT_BODY TRUE
J 0
(-7750 500);
DISPLAY 0.744681 (-7750 500);
DISPLAY INVISIBLE (-7750 500);
WIRE 16 -1 (-5775 1600)(-5875 1600);
WIRE 16 -1 (-5875 1600)(-5875 1450);
WIRE 16 -1 (-5075 1600)(-5075 1425);
WIRE 16 -1 (-5225 1600)(-5075 1600);
WIRE 16 -1 (-6150 875)(-6150 725);
WIRE 16 -1 (-4875 875)(-4875 725);
WIRE 16 -1 (-3825 850)(-3825 1025);
WIRE 16 -1 (-2725 850)(-2725 1050);
WIRE 16 -1 (-8500 2825)(-8500 2875);
WIRE 16 -1 (-8500 2975)(-8500 2875);
WIRE 16 -1 (-8500 2875)(-8675 2875);
WIRE 16 -1 (-8675 2825)(-8675 2875);
WIRE 16 -1 (-8675 2875)(-8850 2875);
WIRE 16 -1 (-8850 2825)(-8850 2875);
WIRE 16 -1 (-8850 2875)(-9025 2875);
WIRE 16 -1 (-9025 2825)(-9025 2875);
WIRE 16 -1 (-7600 2050)(-7350 2050);
WIRE 16 -1 (-7350 2100)(-7350 2050);
WIRE 16 -1 (-7350 2050)(-7350 2000);
WIRE 16 -1 (-7600 2000)(-7350 2000);
WIRE 16 -1 (-7350 1850)(-7350 2000);
WIRE 16 -1 (-7600 1850)(-7350 1850);
WIRE 16 -1 (-7350 1800)(-7350 1850);
WIRE 16 -1 (-7600 1800)(-7350 1800);
WIRE 16 -1 (-7350 1750)(-7350 1800);
WIRE 16 -1 (-7600 1750)(-7350 1750);
WIRE 16 -1 (-7350 1700)(-7350 1750);
WIRE 16 -1 (-7600 1700)(-7350 1700);
WIRE 16 -1 (-7350 1650)(-7350 1700);
WIRE 16 -1 (-7600 1650)(-7350 1650);
WIRE 16 -1 (-7350 1600)(-7350 1650);
WIRE 16 -1 (-7600 1600)(-7350 1600);
WIRE 16 -1 (-7350 1550)(-7350 1600);
WIRE 16 -1 (-7600 1550)(-7350 1550);
WIRE 16 -1 (-7350 1500)(-7350 1550);
WIRE 16 -1 (-7600 1500)(-7350 1500);
WIRE 16 -1 (-7350 1450)(-7350 1500);
WIRE 16 -1 (-7600 1450)(-7350 1450);
WIRE 16 -1 (-7350 1400)(-7350 1450);
WIRE 16 -1 (-7600 1400)(-7350 1400);
WIRE 16 -1 (-7350 1350)(-7350 1400);
WIRE 16 -1 (-7600 1350)(-7350 1350);
WIRE 16 -1 (-7350 1300)(-7350 1350);
WIRE 16 -1 (-7600 1300)(-7350 1300);
WIRE 16 -1 (-7350 1250)(-7350 1300);
WIRE 16 -1 (-7600 1250)(-7350 1250);
WIRE 16 -1 (-7325 925)(-7325 975);
WIRE 16 -1 (-7550 975)(-7325 975);
WIRE 16 -1 (-7550 925)(-7550 975);
WIRE 16 -1 (-7825 975)(-7550 975);
WIRE 16 -1 (-7825 950)(-7825 975);
WIRE 16 -1 (-8525 6225)(-8525 6275);
WIRE 16 -1 (-8525 6375)(-8525 6275);
WIRE 16 -1 (-8525 6275)(-8700 6275);
WIRE 16 -1 (-8700 6225)(-8700 6275);
WIRE 16 -1 (-8950 5400)(-9050 5400);
WIRE 16 -1 (-9050 5400)(-9050 5300);
WIRE 16 -1 (-9050 5300)(-9050 5200);
WIRE 16 -1 (-8950 5300)(-9050 5300);
WIRE 16 -1 (-8950 5200)(-9050 5200);
WIRE 16 -1 (-9050 5200)(-9050 5075);
WIRE 16 -1 (-2725 2200)(-2250 2200);
FORCEPROP 2 LAST SIG_NAME XTAL_CPU0_X32K_X2
J 0
(-2710 2210);
DISPLAY 0.489362 (-2710 2210);
WIRE 16 -1 (-2725 1825)(-2725 2200);
WIRE 16 -1 (-3175 1825)(-2725 1825);
WIRE 16 -1 (-2725 1825)(-2725 1525);
WIRE 16 -1 (-2725 1525)(-2725 1250);
WIRE 16 -1 (-3175 1525)(-2725 1525);
WIRE 16 -1 (-3825 2250)(-2250 2250);
FORCEPROP 2 LAST SIG_NAME XTAL_CPU0_X32K_X1
J 0
(-2710 2260);
DISPLAY 0.489362 (-2710 2260);
WIRE 16 -1 (-3825 1825)(-3825 2250);
WIRE 16 -1 (-3375 1825)(-3825 1825);
WIRE 16 -1 (-3825 1825)(-3825 1525);
WIRE 16 -1 (-3375 1525)(-3825 1525);
WIRE 16 -1 (-3825 1525)(-3825 1225);
WIRE 16 -1 (-7650 2450)(-8850 2450);
FORCEPROP 2 LAST SIG_NAME I3C_1_SPD_DDRGL_CPU0_R_SCL
J 2
(-7710 2460);
DISPLAY 0.489362 (-7710 2460);
WIRE 16 -1 (-8850 2625)(-8850 2450);
WIRE 16 -1 (-8675 2625)(-8675 2500);
WIRE 16 -1 (-8675 2500)(-7650 2500);
FORCEPROP 2 LAST SIG_NAME I3C_0_SPD_DDRAF_CPU0_R_SDA
J 2
(-7710 2510);
DISPLAY 0.489362 (-7710 2510);
WIRE 16 -1 (-7650 2400)(-9025 2400);
FORCEPROP 2 LAST SIG_NAME I3C_1_SPD_DDRGL_CPU0_R_SDA
J 2
(-7710 2410);
DISPLAY 0.489362 (-7710 2410);
WIRE 16 -1 (-9025 2625)(-9025 2400);
WIRE 16 -1 (-8500 2550)(-7650 2550);
FORCEPROP 2 LAST SIG_NAME I3C_0_SPD_DDRAF_CPU0_R_SCL
J 2
(-7710 2560);
DISPLAY 0.489362 (-7710 2560);
WIRE 16 -1 (-8500 2625)(-8500 2550);
WIRE 16 -1 (-7800 1600)(-8625 1600);
FORCEPROP 2 LAST SIG_NAME CPU0_FPGA_SPARE_2
J 0
(-8510 1610);
DISPLAY 0.489362 (-8510 1610);
WIRE 16 -1 (-7800 1550)(-8625 1550);
FORCEPROP 2 LAST SIG_NAME CPU0_FPGA_SPARE_3
J 0
(-8510 1560);
DISPLAY 0.489362 (-8510 1560);
WIRE 16 -1 (-7825 750)(-7825 725);
WIRE 16 -1 (-7825 725)(-7825 600);
WIRE 16 -1 (-7825 725)(-8650 725);
FORCEPROP 2 LAST SIG_NAME RST_CPU0_RSMRST_N
J 0
(-8550 735);
DISPLAY 0.489362 (-8550 735);
WIRE 16 -1 (-7325 625)(-7325 725);
WIRE 16 -1 (-7325 575)(-7325 625);
WIRE 16 -1 (-7325 625)(-8650 625);
FORCEPROP 2 LAST SIG_NAME CPU0_PWR_GD_OUT
J 0
(-8550 635);
DISPLAY 0.489362 (-8550 635);
WIRE 16 -1 (-7800 1500)(-8625 1500);
FORCEPROP 2 LAST SIG_NAME CPU0_SLP_S5_N
J 0
(-8510 1510);
DISPLAY 0.489362 (-8510 1510);
WIRE 16 -1 (-7800 1450)(-8625 1450);
FORCEPROP 2 LAST SIG_NAME CPU0_SLP_S3_N
J 0
(-8510 1460);
DISPLAY 0.489362 (-8510 1460);
WIRE 16 -1 (-7800 1400)(-8625 1400);
FORCEPROP 2 LAST SIG_NAME CPU0_SMERR_N
J 0
(-8510 1410);
DISPLAY 0.489362 (-8510 1410);
WIRE 16 -1 (-7800 1350)(-8625 1350);
FORCEPROP 2 LAST SIG_NAME CPU0_SPD_HOST_CTRL_N
J 2
(-8060 1360);
DISPLAY 0.489362 (-8060 1360);
WIRE 16 -1 (-7800 1300)(-8625 1300);
FORCEPROP 2 LAST SIG_NAME CPU0_NV_SAVE_N
J 0
(-8510 1310);
DISPLAY 0.489362 (-8510 1310);
WIRE 16 -1 (-7800 1250)(-8625 1250);
FORCEPROP 2 LAST SIG_NAME FM_INT_CPU0_HP_UBM_N
J 2
(-8060 1260);
DISPLAY 0.489362 (-8060 1260);
WIRE 16 -1 (-5600 1200)(-6150 1200);
WIRE 16 -1 (-6150 1200)(-6150 1075);
WIRE 16 -1 (-6150 1800)(-6150 1200);
WIRE 16 -1 (-5775 1800)(-6150 1800);
WIRE 16 -1 (-6150 1800)(-6150 2250);
WIRE 16 -1 (-6150 2250)(-4525 2250);
FORCEPROP 2 LAST SIG_NAME XTAL_CPU0_X48M_X1
J 0
(-4910 2260);
DISPLAY 0.489362 (-4910 2260);
WIRE 16 -1 (-8650 675)(-7550 675);
FORCEPROP 2 LAST SIG_NAME CPU0_PWR_GOOD
J 0
(-8550 685);
DISPLAY 0.489362 (-8550 685);
WIRE 16 -1 (-7550 675)(-7550 725);
WIRE 16 -1 (-7550 575)(-7550 675);
WIRE 16 -1 (-7800 1650)(-8625 1650);
FORCEPROP 2 LAST SIG_NAME CPU0_FPGA_SPARE_1
J 0
(-8510 1660);
DISPLAY 0.489362 (-8510 1660);
WIRE 16 -1 (-7800 1700)(-8625 1700);
FORCEPROP 2 LAST SIG_NAME CPU0_FPGA_SPARE_0
J 0
(-8510 1710);
DISPLAY 0.489362 (-8510 1710);
WIRE 16 -1 (-3025 5750)(-1825 5750);
FORCEPROP 2 LAST SIG_NAME PWRGD_CPU0_PWROK
J 0
(-2835 5760);
DISPLAY 0.489362 (-2835 5760);
WIRE 16 -1 (-575 5500)(-3025 5500);
FORCEPROP 2 LAST SIG_NAME IRQ_WAKE_N
J 0
(-2835 5510);
DISPLAY 0.489362 (-2835 5510);
WIRE 16 -1 (-7800 5400)(-8400 5400);
FORCEPROP 2 LAST SIG_NAME CPU0_PWR_BTN_N
J 0
(-8325 5410);
DISPLAY 0.489362 (-8325 5410);
WIRE 16 -1 (-8700 6025)(-8700 5900);
WIRE 16 -1 (-8700 5900)(-7675 5900);
FORCEPROP 2 LAST SIG_NAME RST_CPU0_SYS_N
J 0
(-8235 5910);
DISPLAY 0.489362 (-8235 5910);
WIRE 16 -1 (-8525 6025)(-8525 5950);
WIRE 16 -1 (-8525 5950)(-7675 5950);
FORCEPROP 2 LAST SIG_NAME CPU0_PWR_BTN_N
J 0
(-8235 5960);
DISPLAY 0.489362 (-8235 5960);
WIRE 16 -1 (-7800 5300)(-8400 5300);
FORCEPROP 2 LAST SIG_NAME RST_CPU0_SYS_N
J 0
(-8325 5310);
DISPLAY 0.489362 (-8325 5310);
WIRE 16 -1 (-1625 6100)(-825 6100);
FORCEPROP 2 LAST SIG_NAME CLK_100M_REF_IN_DP
J 0
(-1460 6110);
DISPLAY 0.489362 (-1460 6110);
WIRE 16 -1 (-1625 6050)(-825 6050);
FORCEPROP 2 LAST SIG_NAME CLK_100M_REF_IN_DN
J 0
(-1460 6060);
DISPLAY 0.489362 (-1460 6060);
WIRE 16 -1 (-1400 5600)(-2000 5600);
FORCEPROP 2 LAST SIG_NAME CPU1_PWR_GD_IN
J 0
(-1860 5610);
DISPLAY 0.489362 (-1860 5610);
WIRE 16 -1 (-1950 4100)(-1225 4100);
FORCEPROP 2 LAST SIG_NAME CLK_100M_CPU0_CLK11_DN
J 0
(-1785 4110);
DISPLAY 0.489362 (-1785 4110);
WIRE 16 -1 (-1950 4150)(-1225 4150);
FORCEPROP 2 LAST SIG_NAME CLK_100M_CPU0_CLK11_DP
J 0
(-1785 4160);
DISPLAY 0.489362 (-1785 4160);
WIRE 16 -1 (-3025 5850)(-1825 5850);
FORCEPROP 2 LAST SIG_NAME RST_CPU0_RESETL_N
J 0
(-2835 5860);
DISPLAY 0.489362 (-2835 5860);
WIRE 16 -1 (-3025 6100)(-1825 6100);
FORCEPROP 2 LAST SIG_NAME CLK_100M_REF_OUT_DP
J 0
(-2835 6110);
DISPLAY 0.489362 (-2835 6110);
FORCEPROP 2 LASTPROP $XRERR UNIQUE?
J 0
(-3075 6110);
DISPLAY 0.638298 (-3075 6110);
PAINT MONO (-3075 6110);
DISPLAY INVISIBLE (-3075 6110);
WIRE 16 -1 (-3025 6050)(-1825 6050);
FORCEPROP 2 LAST SIG_NAME CLK_100M_REF_OUT_DN
J 0
(-2835 6060);
DISPLAY 0.489362 (-2835 6060);
FORCEPROP 2 LASTPROP $XRERR UNIQUE?
J 0
(-3075 6060);
DISPLAY 0.638298 (-3075 6060);
PAINT MONO (-3075 6060);
DISPLAY INVISIBLE (-3075 6060);
WIRE 16 -1 (-3025 5150)(-2225 5150);
FORCEPROP 2 LAST SIG_NAME RST_CPU0_PERST0_N
J 0
(-2860 5160);
DISPLAY 0.489362 (-2860 5160);
WIRE 16 -1 (-3025 5300)(-2250 5300);
FORCEPROP 2 LAST SIG_NAME CPU0_NV_SAVE_N
J 0
(-2835 5310);
DISPLAY 0.489362 (-2835 5310);
WIRE 16 -1 (-3025 5400)(-2250 5400);
FORCEPROP 2 LAST SIG_NAME CPU0_FORCE_SELFREFRESH
J 0
(-2835 5410);
DISPLAY 0.489362 (-2835 5410);
WIRE 16 -1 (-3025 5950)(-2225 5950);
FORCEPROP 2 LAST SIG_NAME CLK_CPU0_RTCCLK
J 0
(-2835 5960);
DISPLAY 0.489362 (-2835 5960);
WIRE 16 -1 (-3025 5600)(-2200 5600);
FORCEPROP 2 LAST SIG_NAME CPU0_PWR_GD_OUT
J 0
(-2835 5610);
DISPLAY 0.489362 (-2835 5610);
FORCEPROP 2 LASTPROP $XR0 28 
J 0
(-3110 5610);
DISPLAY 0.638298 (-3110 5610);
PAINT MONO (-3110 5610);
WIRE 16 -1 (-3025 5100)(-2225 5100);
FORCEPROP 2 LAST SIG_NAME RST_CPU0_PERST1_N
J 0
(-2860 5110);
DISPLAY 0.489362 (-2860 5110);
WIRE 16 -1 (-2150 4100)(-3025 4100);
FORCEPROP 2 LAST SIG_NAME CLK_100M_CPU0_CLK11_R_DN
J 0
(-2885 4110);
DISPLAY 0.489362 (-2885 4110);
FORCEPROP 2 LASTPROP $XRERR UNIQUE?
J 0
(-3125 4110);
DISPLAY 0.638298 (-3125 4110);
PAINT MONO (-3125 4110);
DISPLAY INVISIBLE (-3125 4110);
WIRE 16 -1 (-2150 4150)(-3025 4150);
FORCEPROP 2 LAST SIG_NAME CLK_100M_CPU0_CLK11_R_DP
J 0
(-2885 4160);
DISPLAY 0.489362 (-2885 4160);
FORCEPROP 2 LASTPROP $XRERR UNIQUE?
J 0
(-3125 4160);
DISPLAY 0.638298 (-3125 4160);
PAINT MONO (-3125 4160);
DISPLAY INVISIBLE (-3125 4160);
WIRE 16 -1 (-1950 3500)(-1150 3500);
FORCEPROP 2 LAST SIG_NAME CLK_100M_CPU0_CLK15_DN
J 0
(-1785 3510);
DISPLAY 0.489362 (-1785 3510);
WIRE 16 -1 (-1950 3550)(-1150 3550);
FORCEPROP 2 LAST SIG_NAME CLK_100M_CPU0_CLK15_DP
J 0
(-1785 3560);
DISPLAY 0.489362 (-1785 3560);
WIRE 16 -1 (-1950 3800)(-1175 3800);
FORCEPROP 2 LAST SIG_NAME CLK_100M_CPU0_CLK13_DN
J 0
(-1785 3810);
DISPLAY 0.489362 (-1785 3810);
WIRE 16 -1 (-1950 3850)(-1175 3850);
FORCEPROP 2 LAST SIG_NAME CLK_100M_CPU0_CLK13_DP
J 0
(-1785 3860);
DISPLAY 0.489362 (-1785 3860);
WIRE 16 -1 (-3025 3100)(-2100 3100);
FORCEPROP 2 LAST SIG_NAME SMB_CPU0_SEC_SDA
J 2
(-2275 3110);
DISPLAY 0.489362 (-2275 3110);
WIRE 16 -1 (-3025 3150)(-2100 3150);
FORCEPROP 2 LAST SIG_NAME SMB_CPU0_SEC_SCL
J 2
(-2275 3160);
DISPLAY 0.489362 (-2275 3160);
WIRE 16 -1 (-3025 3500)(-2150 3500);
FORCEPROP 2 LAST SIG_NAME CLK_100M_CPU0_CLK15_R_DN
J 0
(-2885 3510);
DISPLAY 0.489362 (-2885 3510);
FORCEPROP 2 LASTPROP $XRERR UNIQUE?
J 0
(-3125 3510);
DISPLAY 0.638298 (-3125 3510);
PAINT MONO (-3125 3510);
DISPLAY INVISIBLE (-3125 3510);
WIRE 16 -1 (-3025 3550)(-2150 3550);
FORCEPROP 2 LAST SIG_NAME CLK_100M_CPU0_CLK15_R_DP
J 0
(-2885 3560);
DISPLAY 0.489362 (-2885 3560);
FORCEPROP 2 LASTPROP $XRERR UNIQUE?
J 0
(-3125 3560);
DISPLAY 0.638298 (-3125 3560);
PAINT MONO (-3125 3560);
DISPLAY INVISIBLE (-3125 3560);
WIRE 16 -1 (-3025 3800)(-2150 3800);
FORCEPROP 2 LAST SIG_NAME CLK_100M_CPU0_CLK13_R_DN
J 0
(-2885 3810);
DISPLAY 0.489362 (-2885 3810);
FORCEPROP 2 LASTPROP $XRERR UNIQUE?
J 0
(-3125 3810);
DISPLAY 0.638298 (-3125 3810);
PAINT MONO (-3125 3810);
DISPLAY INVISIBLE (-3125 3810);
WIRE 16 -1 (-3025 3850)(-2150 3850);
FORCEPROP 2 LAST SIG_NAME CLK_100M_CPU0_CLK13_R_DP
J 0
(-2885 3860);
DISPLAY 0.489362 (-2885 3860);
FORCEPROP 2 LASTPROP $XRERR UNIQUE?
J 0
(-3125 3860);
DISPLAY 0.638298 (-3125 3860);
PAINT MONO (-3125 3860);
DISPLAY INVISIBLE (-3125 3860);
WIRE 16 -1 (-6250 5400)(-5525 5400);
FORCEPROP 2 LAST SIG_NAME CPU0_PWR_GOOD
J 0
(-6160 5410);
DISPLAY 0.489362 (-6160 5410);
WIRE 16 -1 (-5525 5500)(-6250 5500);
FORCEPROP 2 LAST SIG_NAME RST_CPU0_RSMRST_N
J 0
(-6175 5510);
DISPLAY 0.489362 (-6175 5510);
WIRE 16 -1 (-5525 5550)(-6250 5550);
FORCEPROP 2 LAST SIG_NAME RST_CPU0_SYS_N
J 0
(-6175 5560);
DISPLAY 0.489362 (-6175 5560);
WIRE 16 -1 (-5525 5600)(-6250 5600);
FORCEPROP 2 LAST SIG_NAME CPU0_PWR_BTN_N
J 0
(-6175 5610);
DISPLAY 0.489362 (-6175 5610);
WIRE 16 -1 (-5525 4850)(-7775 4850);
FORCEPROP 2 LAST SIG_NAME FM_INT_CPU0_HP_UBM_N
J 2
(-7160 4860);
DISPLAY 0.489362 (-7160 4860);
WIRE 16 -1 (-6675 4250)(-5525 4250);
FORCEPROP 2 LAST SIG_NAME I3C_1_SPD_DDRGL_CPU0_R_SDA
J 0
(-6275 4260);
DISPLAY 0.489362 (-6275 4260);
WIRE 16 -1 (-5525 4300)(-6675 4300);
FORCEPROP 2 LAST SIG_NAME I3C_1_SPD_DDRGL_CPU0_R_SCL
J 0
(-6275 4310);
DISPLAY 0.489362 (-6275 4310);
WIRE 16 -1 (-6675 4350)(-5525 4350);
FORCEPROP 2 LAST SIG_NAME I3C_0_SPD_DDRAF_CPU0_R_SDA
J 0
(-6275 4360);
DISPLAY 0.489362 (-6275 4360);
WIRE 16 -1 (-5525 4400)(-6675 4400);
FORCEPROP 2 LAST SIG_NAME I3C_0_SPD_DDRAF_CPU0_R_SCL
J 0
(-6275 4410);
DISPLAY 0.489362 (-6275 4410);
WIRE 16 -1 (-5525 5200)(-6250 5200);
FORCEPROP 2 LAST SIG_NAME XTAL_CPU0_X48M_X2
J 0
(-6160 5210);
DISPLAY 0.489362 (-6160 5210);
WIRE 16 -1 (-6250 5250)(-5525 5250);
FORCEPROP 2 LAST SIG_NAME XTAL_CPU0_X48M_X1
J 0
(-6160 5260);
DISPLAY 0.489362 (-6160 5260);
WIRE 16 -1 (-5525 4650)(-6575 4650);
FORCEPROP 2 LAST SIG_NAME CPU0_NMI_SYNC_FLOOD_N
J 0
(-6460 4660);
DISPLAY 0.489362 (-6460 4660);
WIRE 16 -1 (-5525 5000)(-6250 5000);
FORCEPROP 2 LAST SIG_NAME XTAL_CPU0_X32K_X2
J 0
(-6160 5010);
DISPLAY 0.489362 (-6160 5010);
WIRE 16 -1 (-6250 5050)(-5525 5050);
FORCEPROP 2 LAST SIG_NAME XTAL_CPU0_X32K_X1
J 0
(-6160 5060);
DISPLAY 0.489362 (-6160 5060);
WIRE 16 -1 (-6325 5750)(-5525 5750);
FORCEPROP 2 LAST SIG_NAME CPU0_SLP_S5_N
J 0
(-6175 5760);
DISPLAY 0.489362 (-6175 5760);
FORCEPROP 2 LASTPROP $XR0 28 
J 0
(-6445 5760);
DISPLAY 0.638298 (-6445 5760);
PAINT MONO (-6445 5760);
WIRE 16 -1 (-5525 5700)(-6325 5700);
FORCEPROP 2 LAST SIG_NAME CPU0_SLP_S3_N
J 0
(-6175 5710);
DISPLAY 0.489362 (-6175 5710);
FORCEPROP 2 LASTPROP $XR0 28 
J 0
(-6445 5710);
DISPLAY 0.638298 (-6445 5710);
PAINT MONO (-6445 5710);
WIRE 16 -1 (-6675 4200)(-5525 4200);
FORCEPROP 2 LAST SIG_NAME SMB_CPU0_2_R_SCL
J 0
(-6275 4210);
DISPLAY 0.489362 (-6275 4210);
FORCEPROP 2 LASTPROP $XRERR UNIQUE?
J 0
(-6515 4210);
DISPLAY 0.638298 (-6515 4210);
PAINT MONO (-6515 4210);
DISPLAY INVISIBLE (-6515 4210);
WIRE 16 -1 (-6675 4150)(-5525 4150);
FORCEPROP 2 LAST SIG_NAME SMB_CPU0_2_R_SDA
J 0
(-6275 4160);
DISPLAY 0.489362 (-6275 4160);
FORCEPROP 2 LASTPROP $XRERR UNIQUE?
J 0
(-6515 4160);
DISPLAY 0.638298 (-6515 4160);
PAINT MONO (-6515 4160);
DISPLAY INVISIBLE (-6515 4160);
WIRE 16 -1 (-6675 4100)(-5525 4100);
FORCEPROP 2 LAST SIG_NAME SMB_CPU0_3_R_SCL
J 0
(-6275 4110);
DISPLAY 0.489362 (-6275 4110);
FORCEPROP 2 LASTPROP $XRERR UNIQUE?
J 0
(-6515 4110);
DISPLAY 0.638298 (-6515 4110);
PAINT MONO (-6515 4110);
DISPLAY INVISIBLE (-6515 4110);
WIRE 16 -1 (-7100 5700)(-6525 5700);
FORCEPROP 2 LAST SIG_NAME FM_CPU0_SLP_S3_N
J 0
(-7060 5725);
DISPLAY 0.489362 (-7060 5725);
WIRE 16 -1 (-7100 5750)(-6525 5750);
FORCEPROP 2 LAST SIG_NAME FM_CPU0_SLP_S5_N
J 0
(-7060 5775);
DISPLAY 0.489362 (-7060 5775);
WIRE 16 -1 (-6875 4200)(-7775 4200);
FORCEPROP 2 LAST SIG_NAME SMB_CPU0_2_SCL
J 0
(-7625 4210);
DISPLAY 0.489362 (-7625 4210);
WIRE 16 -1 (-6875 4150)(-7775 4150);
FORCEPROP 2 LAST SIG_NAME SMB_CPU0_2_SDA
J 0
(-7625 4160);
DISPLAY 0.489362 (-7625 4160);
WIRE 16 -1 (-6875 4100)(-7775 4100);
FORCEPROP 2 LAST SIG_NAME SMB_CPU0_3_SCL
J 0
(-7625 4110);
DISPLAY 0.489362 (-7625 4110);
WIRE 16 -1 (-4875 2200)(-4525 2200);
WIRE 16 -1 (-4875 1800)(-4875 2200);
FORCEPROP 2 LAST SIG_NAME XTAL_CPU0_X48M_X2
J 0
(-4910 2210);
DISPLAY 0.489362 (-4910 2210);
WIRE 16 -1 (-5225 1800)(-4875 1800);
WIRE 16 -1 (-4875 1800)(-4875 1200);
WIRE 16 -1 (-4875 1200)(-4875 1075);
WIRE 16 -1 (-5400 1200)(-4875 1200);
WIRE 16 -1 (-7150 3450)(-5525 3450);
FORCEPROP 2 LAST SIG_NAME CPU0_SPD_HOST_CTRL_N
J 0
(-7125 3460);
DISPLAY 0.489362 (-7125 3460);
WIRE 16 -1 (-7150 2900)(-5525 2900);
FORCEPROP 2 LAST SIG_NAME BIOS_DEBUG_MODE
J 0
(-7125 2910);
DISPLAY 0.489362 (-7125 2910);
WIRE 16 -1 (-7175 3150)(-5525 3150);
FORCEPROP 2 LAST SIG_NAME SLOT1_BUF_SKU_ID0
J 0
(-7125 3160);
DISPLAY 0.489362 (-7125 3160);
WIRE 16 -1 (-7175 3100)(-5525 3100);
FORCEPROP 2 LAST SIG_NAME SLOT1_BUF_SKU_ID1
J 0
(-7125 3110);
DISPLAY 0.489362 (-7125 3110);
WIRE 16 -1 (-5525 3700)(-6225 3700);
FORCEPROP 2 LAST SIG_NAME CPU0_SMERR_N
J 0
(-6085 3710);
DISPLAY 0.489362 (-6085 3710);
WIRE 16 -1 (-5525 3200)(-7175 3200);
FORCEPROP 2 LAST SIG_NAME CPU0_FPGA_SPARE_3
J 0
(-7125 3210);
DISPLAY 0.489362 (-7125 3210);
WIRE 16 -1 (-5525 3250)(-7175 3250);
FORCEPROP 2 LAST SIG_NAME CPU0_FPGA_SPARE_2
J 0
(-7125 3260);
DISPLAY 0.489362 (-7125 3260);
WIRE 16 -1 (-5525 3300)(-7175 3300);
FORCEPROP 2 LAST SIG_NAME CPU0_FPGA_SPARE_1
J 0
(-7125 3310);
DISPLAY 0.489362 (-7125 3310);
WIRE 16 -1 (-5525 3350)(-7175 3350);
FORCEPROP 2 LAST SIG_NAME CPU0_FPGA_SPARE_0
J 0
(-7125 3360);
DISPLAY 0.489362 (-7125 3360);
WIRE 16 -1 (-5525 2750)(-7150 2750);
FORCEPROP 2 LAST SIG_NAME CPU0_ROM_TYPE_SELECT
J 0
(-7125 2760);
DISPLAY 0.489362 (-7125 2760);
WIRE 16 -1 (-5525 3850)(-6675 3850);
FORCEPROP 2 LAST SIG_NAME SMB_CPU_5_R_SDA
J 0
(-6285 3860);
DISPLAY 0.489362 (-6285 3860);
FORCEPROP 2 LASTPROP $XRERR UNIQUE?
J 0
(-6525 3860);
DISPLAY 0.638298 (-6525 3860);
PAINT MONO (-6525 3860);
DISPLAY INVISIBLE (-6525 3860);
WIRE 16 -1 (-5525 3400)(-6200 3400);
FORCEPROP 2 LAST SIG_NAME FM_PASSWORD_CLEAR_R_N
J 0
(-6125 3410);
DISPLAY 0.489362 (-6125 3410);
FORCEPROP 2 LASTPROP $XRERR UNIQUE?
J 0
(-6365 3410);
DISPLAY 0.638298 (-6365 3410);
PAINT MONO (-6365 3410);
DISPLAY INVISIBLE (-6365 3410);
WIRE 16 -1 (-5525 3000)(-6200 3000);
FORCEPROP 2 LAST SIG_NAME FM_BIOS_POST_CMPLT_R_N
J 0
(-6110 3010);
DISPLAY 0.489362 (-6110 3010);
FORCEPROP 2 LASTPROP $XRERR UNIQUE?
J 0
(-6350 3010);
DISPLAY 0.638298 (-6350 3010);
PAINT MONO (-6350 3010);
DISPLAY INVISIBLE (-6350 3010);
WIRE 16 -1 (-5525 3900)(-6675 3900);
FORCEPROP 2 LAST SIG_NAME SMB_CPU_5_R_SCL
J 0
(-6285 3910);
DISPLAY 0.489362 (-6285 3910);
FORCEPROP 2 LASTPROP $XRERR UNIQUE?
J 0
(-6525 3910);
DISPLAY 0.638298 (-6525 3910);
PAINT MONO (-6525 3910);
DISPLAY INVISIBLE (-6525 3910);
WIRE 16 -1 (-6675 4050)(-5525 4050);
FORCEPROP 2 LAST SIG_NAME SMB_CPU0_3_R_SDA
J 0
(-6275 4060);
DISPLAY 0.489362 (-6275 4060);
FORCEPROP 2 LASTPROP $XRERR UNIQUE?
J 0
(-6515 4060);
DISPLAY 0.638298 (-6515 4060);
PAINT MONO (-6515 4060);
DISPLAY INVISIBLE (-6515 4060);
WIRE 16 -1 (-6675 4000)(-5525 4000);
FORCEPROP 2 LAST SIG_NAME SMB_CPU0_4_R_SCL
J 0
(-6275 4010);
DISPLAY 0.489362 (-6275 4010);
FORCEPROP 2 LASTPROP $XRERR UNIQUE?
J 0
(-6515 4010);
DISPLAY 0.638298 (-6515 4010);
PAINT MONO (-6515 4010);
DISPLAY INVISIBLE (-6515 4010);
WIRE 16 -1 (-6675 3950)(-5525 3950);
FORCEPROP 2 LAST SIG_NAME SMB_CPU0_4_R_SDA
J 0
(-6275 3960);
DISPLAY 0.489362 (-6275 3960);
FORCEPROP 2 LASTPROP $XRERR UNIQUE?
J 0
(-6515 3960);
DISPLAY 0.638298 (-6515 3960);
PAINT MONO (-6515 3960);
DISPLAY INVISIBLE (-6515 3960);
WIRE 16 -1 (-5525 2950)(-6200 2950);
FORCEPROP 2 LAST SIG_NAME BOOT_RDY_R_H
J 0
(-6110 2960);
DISPLAY 0.489362 (-6110 2960);
FORCEPROP 2 LASTPROP $XRERR UNIQUE?
J 0
(-6350 2960);
DISPLAY 0.638298 (-6350 2960);
PAINT MONO (-6350 2960);
DISPLAY INVISIBLE (-6350 2960);
WIRE 16 -1 (-7150 2950)(-6400 2950);
FORCEPROP 2 LAST SIG_NAME BOOT_RDY_H
J 0
(-7125 2960);
DISPLAY 0.489362 (-7125 2960);
WIRE 16 -1 (-6400 3000)(-7150 3000);
FORCEPROP 2 LAST SIG_NAME FM_BIOS_POST_CMPLT_N
J 0
(-7125 3010);
DISPLAY 0.489362 (-7125 3010);
WIRE 16 -1 (-6875 3950)(-7775 3950);
FORCEPROP 2 LAST SIG_NAME SMB_CPU0_4_SDA
J 0
(-7625 3960);
DISPLAY 0.489362 (-7625 3960);
WIRE 16 -1 (-6875 4000)(-7775 4000);
FORCEPROP 2 LAST SIG_NAME SMB_CPU0_4_SCL
J 0
(-7625 4010);
DISPLAY 0.489362 (-7625 4010);
WIRE 16 -1 (-7175 3400)(-6400 3400);
FORCEPROP 2 LAST SIG_NAME FM_PASSWORD_CLEAR_N
J 0
(-7125 3410);
DISPLAY 0.489362 (-7125 3410);
WIRE 16 -1 (-7775 3900)(-6875 3900);
FORCEPROP 2 LAST SIG_NAME SMB_CPU_5_SCL
J 0
(-7600 3910);
DISPLAY 0.489362 (-7600 3910);
WIRE 16 -1 (-7775 3850)(-6875 3850);
FORCEPROP 2 LAST SIG_NAME SMB_CPU_5_SDA
J 0
(-7600 3860);
DISPLAY 0.489362 (-7600 3860);
WIRE 16 -1 (-6875 4050)(-7775 4050);
FORCEPROP 2 LAST SIG_NAME SMB_CPU0_3_SDA
J 0
(-7625 4060);
DISPLAY 0.489362 (-7625 4060);
WIRE 16 -1 (-8625 2050)(-7800 2050);
FORCEPROP 2 LAST SIG_NAME BOOT_RDY_H
J 0
(-8510 2060);
DISPLAY 0.489362 (-8510 2060);
WIRE 16 -1 (-7800 1750)(-8625 1750);
FORCEPROP 2 LAST SIG_NAME PWRGD_CPU0_PWROK
J 0
(-8510 1760);
DISPLAY 0.489362 (-8510 1760);
WIRE 16 -1 (-7800 1800)(-8625 1800);
FORCEPROP 2 LAST SIG_NAME RST_CPU0_RESETL_N
J 0
(-8510 1810);
DISPLAY 0.489362 (-8510 1810);
WIRE 16 -1 (-7800 1850)(-8625 1850);
FORCEPROP 2 LAST SIG_NAME CPU0_NMI_SYNC_FLOOD_N
J 0
(-8510 1860);
DISPLAY 0.489362 (-8510 1860);
WIRE 16 -1 (-7800 2000)(-8625 2000);
FORCEPROP 2 LAST SIG_NAME CPU0_FORCE_SELFREFRESH
J 0
(-8510 2010);
DISPLAY 0.489362 (-8510 2010);
DOT 1 (-8500 2875);
DOT 1 (-8675 2875);
DOT 1 (-7350 1500);
DOT 1 (-7550 675);
DOT 1 (-7325 625);
DOT 1 (-7350 1550);
DOT 1 (-7550 975);
DOT 1 (-7350 1300);
DOT 1 (-7350 1850);
DOT 1 (-8850 2875);
DOT 1 (-7350 1400);
DOT 1 (-6150 1800);
DOT 1 (-6150 1200);
DOT 1 (-4875 1200);
DOT 1 (-4875 1800);
DOT 1 (-2725 1825);
DOT 1 (-2725 1525);
DOT 1 (-3825 1825);
DOT 1 (-3825 1525);
DOT 1 (-9050 5200);
DOT 1 (-9050 5300);
DOT 1 (-7350 1700);
DOT 1 (-7350 1600);
DOT 1 (-7825 725);
DOT 1 (-8525 6275);
DOT 1 (-7350 2050);
DOT 1 (-7350 2000);
DOT 1 (-7350 1350);
DOT 1 (-7350 1450);
DOT 1 (-7350 1650);
DOT 1 (-7350 1750);
DOT 1 (-7350 1800);
FORCENOTE
$CDS_IMAGE|clipboard_2_8.jpg|2130|975
(-1275 1600) 0;
DISPLAY LEFT (-1275 1600);
QUIT
